P  UNITS CUST 0
C   
C   IPC 356 OUTPUT.  
C
P   NNAME00000     SLOT2_P12V_SENSE_VP_R                                    
P   NNAME00001     SLOT2_P12V_SENSE_VN_R                                    
P   NNAME00002     SLOT3_P12V_SENSE_VP_R                                    
P   NNAME00003     SLOT3_P12V_SENSE_VN_R                                    
P   NNAME00004     ATX_P12V_SENSE_VP_R                                      
P   NNAME00005     ATX_P12V_SENSE_VN_R                                      
P   NNAME00006     USB_HUB_XTAL_IN                                          
P   NNAME00007     USB_HUB_XTAL_OUT                                         
P   NNAME00008     P3E_CPU0_PE2_SS_C_TXP<8>                                 
P   NNAME00009     P3E_CPU0_PE2_SS_C_TXN<8>                                 
P   NNAME00010     P3E_CPU0_PE2_SS_RXP<8>                                   
P   NNAME00011     P3E_CPU0_PE2_SS_RXN<8>                                   
P   NNAME00012     P3E_CPU0_PE2_SS_C_TXP<9>                                 
P   NNAME00013     P3E_CPU0_PE2_SS_C_TXN<9>                                 
P   NNAME00014     P3E_CPU0_PE2_SS_RXP<9>                                   
P   NNAME00015     P3E_CPU0_PE2_SS_RXN<9>                                   
P   NNAME00016     P3E_CPU0_PE2_SS_C_TXP<10>                                
P   NNAME00017     P3E_CPU0_PE2_SS_C_TXN<10>                                
P   NNAME00018     P3E_CPU0_PE2_SS_RXP<10>                                  
P   NNAME00019     P3E_CPU0_PE2_SS_RXN<10>                                  
P   NNAME00020     P3E_CPU0_PE2_SS_C_TXP<11>                                
P   NNAME00021     P3E_CPU0_PE2_SS_C_TXN<11>                                
P   NNAME00022     P3E_CPU0_PE2_SS_RXP<11>                                  
P   NNAME00023     P3E_CPU0_PE2_SS_RXN<11>                                  
P   NNAME00024     P3E_CPU0_PE2_SS_C_TXP<12>                                
P   NNAME00025     P3E_CPU0_PE2_SS_C_TXN<12>                                
P   NNAME00026     P3E_CPU0_PE2_SS_RXP<12>                                  
P   NNAME00027     P3E_CPU0_PE2_SS_RXN<12>                                  
P   NNAME00028     P3E_CPU0_PE2_SS_C_TXP<13>                                
P   NNAME00029     P3E_CPU0_PE2_SS_C_TXN<13>                                
P   NNAME00030     P3E_CPU0_PE2_SS_RXP<13>                                  
P   NNAME00031     P3E_CPU0_PE2_SS_RXN<13>                                  
P   NNAME00032     P3E_CPU0_PE2_SS_C_TXP<14>                                
P   NNAME00033     P3E_CPU0_PE2_SS_C_TXN<14>                                
P   NNAME00034     P3E_CPU0_PE2_SS_RXP<14>                                  
P   NNAME00035     P3E_CPU0_PE2_SS_RXN<14>                                  
P   NNAME00036     P3E_CPU0_PE2_SS_C_TXP<15>                                
P   NNAME00037     P3E_CPU0_PE2_SS_C_TXN<15>                                
P   NNAME00038     P3E_CPU0_PE2_SS_RXP<15>                                  
P   NNAME00039     P3E_CPU0_PE2_SS_RXN<15>                                  
P   NNAME00040     SMB_SLOTX24_STBY_LVC3_SDA_R2                             
P   NNAME00041     IRQ_OOB_MGMT_RISER_ALERT_N                               
P   NNAME00042     SMB_SLOTX24_STBY_LVC3_SCL_R2                             
P   NNAME00043     FM_PWRBRK_SLOT_N                                         
P   NNAME00044     SMB_PCH_ALERT_R_N                                        
P   NNAME00045     FM_PE_SLOTX24_WAKE_N                                     
P   NNAME00046     SMB_HOST_STBY_LVC3_SDA_R5                                
P   NNAME00047     SMB_HOST_STBY_LVC3_SCL_R5                                
P   NNAME00048     CLK_100M_PCH_SLOTX24_S5_DP                               
P   NNAME00049     CLK_100M_PCH_SLOTX24_S5_DN                               
P   NNAME00050     CLK_100M_PCH_SLOTX24_S4_DP                               
P   NNAME00051     CLK_100M_PCH_SLOTX24_S4_DN                               
P   NNAME00052     P3E_CPU0_PE1_PCH_CON_TXP<15>                             
P   NNAME00053     P3E_CPU0_PE1_PCH_CON_TXN<15>                             
P   NNAME00054     P3E_CPU0_PE1_PCH_CON_RXP<15>                             
P   NNAME00055     P3E_CPU0_PE1_PCH_CON_RXN<15>                             
P   NNAME00056     P3E_CPU0_PE1_PCH_CON_TXP<14>                             
P   NNAME00057     P3E_CPU0_PE1_PCH_CON_TXN<14>                             
P   NNAME00058     P3E_CPU0_PE1_PCH_CON_RXP<14>                             
P   NNAME00059     P3E_CPU0_PE1_PCH_CON_RXN<14>                             
P   NNAME00060     P3E_CPU0_PE1_PCH_CON_TXP<13>                             
P   NNAME00061     P3E_CPU0_PE1_PCH_CON_TXN<13>                             
P   NNAME00062     P3E_CPU0_PE1_PCH_CON_RXP<13>                             
P   NNAME00063     P3E_CPU0_PE1_PCH_CON_RXN<13>                             
P   NNAME00064     P3E_CPU0_PE1_PCH_CON_TXP<12>                             
P   NNAME00065     P3E_CPU0_PE1_PCH_CON_TXN<12>                             
P   NNAME00066     P3E_CPU0_PE1_PCH_CON_RXP<12>                             
P   NNAME00067     P3E_CPU0_PE1_PCH_CON_RXN<12>                             
P   NNAME00068     P3E_CPU0_PE1_PCH_CON_TXP<11>                             
P   NNAME00069     P3E_CPU0_PE1_PCH_CON_TXN<11>                             
P   NNAME00070     P3E_CPU0_PE1_PCH_CON_RXP<11>                             
P   NNAME00071     P3E_CPU0_PE1_PCH_CON_RXN<11>                             
P   NNAME00072     P3E_CPU0_PE1_PCH_CON_TXP<10>                             
P   NNAME00073     P3E_CPU0_PE1_PCH_CON_TXN<10>                             
P   NNAME00074     P3E_CPU0_PE1_PCH_CON_RXP<10>                             
P   NNAME00075     P3E_CPU0_PE1_PCH_CON_RXN<10>                             
P   NNAME00076     P3E_CPU0_PE1_PCH_CON_TXP<9>                              
P   NNAME00077     P3E_CPU0_PE1_PCH_CON_TXN<9>                              
P   NNAME00078     P3E_CPU0_PE1_PCH_CON_RXP<9>                              
P   NNAME00079     P3E_CPU0_PE1_PCH_CON_RXN<9>                              
P   NNAME00080     P3E_CPU0_PE1_PCH_CON_TXP<8>                              
P   NNAME00081     P3E_CPU0_PE1_PCH_CON_TXN<8>                              
P   NNAME00082     P3E_CPU0_PE1_PCH_CON_RXP<8>                              
P   NNAME00083     P3E_CPU0_PE1_PCH_CON_RXN<8>                              
P   NNAME00084     P3E_CPU0_PE1_SS_C_TXP<7>                                 
P   NNAME00085     P3E_CPU0_PE1_SS_C_TXN<7>                                 
P   NNAME00086     P3E_CPU0_PE1_SS_C_RXP<7>                                 
P   NNAME00087     P3E_CPU0_PE1_SS_C_RXN<7>                                 
P   NNAME00088     P3E_CPU0_PE1_SS_C_TXP<6>                                 
P   NNAME00089     P3E_CPU0_PE1_SS_C_TXN<6>                                 
P   NNAME00090     P3E_CPU0_PE1_SS_C_RXP<6>                                 
P   NNAME00091     P3E_CPU0_PE1_SS_C_RXN<6>                                 
P   NNAME00092     P3E_CPU0_PE1_SS_C_TXP<5>                                 
P   NNAME00093     P3E_CPU0_PE1_SS_C_TXN<5>                                 
P   NNAME00094     P3E_CPU0_PE1_SS_C_RXP<5>                                 
P   NNAME00095     P3E_CPU0_PE1_SS_C_RXN<5>                                 
P   NNAME00096     P3E_CPU0_PE1_SS_C_TXP<4>                                 
P   NNAME00097     P3E_CPU0_PE1_SS_C_TXN<4>                                 
P   NNAME00098     P3E_CPU0_PE1_SS_C_RXP<4>                                 
P   NNAME00099     P3E_CPU0_PE1_SS_C_RXN<4>                                 
P   NNAME00100     P3E_CPU0_PE1_SS_C_TXP<3>                                 
P   NNAME00101     P3E_CPU0_PE1_SS_C_TXN<3>                                 
P   NNAME00102     P3E_CPU0_PE1_SS_C_RXP<3>                                 
P   NNAME00103     P3E_CPU0_PE1_SS_C_RXN<3>                                 
P   NNAME00104     P3E_CPU0_PE1_SS_C_TXP<2>                                 
P   NNAME00105     P3E_CPU0_PE1_SS_C_TXN<2>                                 
P   NNAME00106     P3E_CPU0_PE1_SS_C_RXP<2>                                 
P   NNAME00107     P3E_CPU0_PE1_SS_C_RXN<2>                                 
P   NNAME00108     P3E_CPU0_PE1_SS_C_TXP<1>                                 
P   NNAME00109     P3E_CPU0_PE1_SS_C_TXN<1>                                 
P   NNAME00110     P3E_CPU0_PE1_SS_C_RXP<1>                                 
P   NNAME00111     P3E_CPU0_PE1_SS_C_RXN<1>                                 
P   NNAME00112     P3E_CPU0_PE1_SS_C_TXP<0>                                 
P   NNAME00113     P3E_CPU0_PE1_SS_C_TXN<0>                                 
P   NNAME00114     P3E_CPU0_PE1_SS_C_RXP<0>                                 
P   NNAME00115     P3E_CPU0_PE1_SS_C_RXN<0>                                 
P   NNAME00116     P3E_CPU0_PE2_SS_C_TXP<0>                                 
P   NNAME00117     P3E_CPU0_PE2_SS_C_TXN<0>                                 
P   NNAME00118     P3E_CPU0_PE2_SS_RXP<0>                                   
P   NNAME00119     P3E_CPU0_PE2_SS_RXN<0>                                   
P   NNAME00120     P3E_CPU0_PE2_SS_C_TXP<1>                                 
P   NNAME00121     P3E_CPU0_PE2_SS_C_TXN<1>                                 
P   NNAME00122     P3E_CPU0_PE2_SS_RXP<1>                                   
P   NNAME00123     P3E_CPU0_PE2_SS_RXN<1>                                   
P   NNAME00124     P3E_CPU0_PE2_SS_C_TXP<2>                                 
P   NNAME00125     P3E_CPU0_PE2_SS_C_TXN<2>                                 
P   NNAME00126     P3E_CPU0_PE2_SS_RXP<2>                                   
P   NNAME00127     P3E_CPU0_PE2_SS_RXN<2>                                   
P   NNAME00128     P3E_CPU0_PE2_SS_C_TXP<3>                                 
P   NNAME00129     P3E_CPU0_PE2_SS_C_TXN<3>                                 
P   NNAME00130     P3E_CPU0_PE2_SS_RXP<3>                                   
P   NNAME00131     P3E_CPU0_PE2_SS_RXN<3>                                   
P   NNAME00132     P3E_CPU0_PE2_SS_C_TXP<4>                                 
P   NNAME00133     P3E_CPU0_PE2_SS_C_TXN<4>                                 
P   NNAME00134     P3E_CPU0_PE2_SS_RXP<4>                                   
P   NNAME00135     P3E_CPU0_PE2_SS_RXN<4>                                   
P   NNAME00136     P3E_CPU0_PE2_SS_C_TXP<5>                                 
P   NNAME00137     P3E_CPU0_PE2_SS_C_TXN<5>                                 
P   NNAME00138     P3E_CPU0_PE2_SS_RXP<5>                                   
P   NNAME00139     P3E_CPU0_PE2_SS_RXN<5>                                   
P   NNAME00140     P3E_CPU0_PE2_SS_C_TXP<6>                                 
P   NNAME00141     P3E_CPU0_PE2_SS_C_TXN<6>                                 
P   NNAME00142     P3E_CPU0_PE2_SS_RXP<6>                                   
P   NNAME00143     P3E_CPU0_PE2_SS_RXN<6>                                   
P   NNAME00144     P3E_CPU0_PE2_SS_C_TXP<7>                                 
P   NNAME00145     P3E_CPU0_PE2_SS_C_TXN<7>                                 
P   NNAME00146     P3E_CPU0_PE2_SS_RXP<7>                                   
P   NNAME00147     P3E_CPU0_PE2_SS_RXN<7>                                   
P   NNAME00148     SMB_PCH_ALERT_N                                          
P   NNAME00149     SMB_VMONITOR_ATX_MUX_SDA                                 
P   NNAME00150     SMDAT_BMC_DEVICE                                         
P   NNAME00151     SMB_VMONITOR_ATX_MUX_SCL                                 
P   NNAME00152     SMCLK_BMC_DEVICE                                         
P   NNAME00153     PCIE_SLOT2_PRSNT2_1_N                                    
P   NNAME00154     PCIE_SLOT2_PRSNT2_2_N                                    
P   NNAME00155     PCIE_SLOT2_PRSNT2_3_N                                    
P   NNAME00156     PCIE_SLOT3_PRSNT2_1_N                                    
P   NNAME00157     PCIE_SLOT3_PRSNT2_2_N                                    
P   NNAME00158     PCIE_SLOT3_PRSNT2_3_N                                    
P   NNAME00159     PCIE_SLOT2_PRSNT2_4_N                                    
P   NNAME00160     PCIE_SLOT3_PRSNT2_4_N                                    
P   NNAME00161     ATX_VMONITOR_A1                                          
P   NNAME00162     ATX_VMONITOR_A0                                          
P   NNAME00163     SMB_VMONITOR_SLOT2_ALERT_N                               
P   NNAME00164     SMB_BMC_DEVICE_ALERT_N                                   
P   NNAME00165     GPIO_B_EXP_INT_N                                         
P   NNAME00166     SMB_PCH_DEVICE_ALERT_N                                   
P   NNAME00167     GPIO_P_EXP_INT_N                                         
P   NNAME00168     SMCLK_PCH_DEVICE                                         
P   NNAME00169     SMDAT_PCH_DEVICE                                         
P   NNAME00170     SMB_VMONITOR_SLOT3_ALERT_N                               
P   NNAME00171     SMB_VMONITOR_ATX_ALERT_N                                 
P   NNAME00172     SMCLK_PCH_SLOT2                                          
P   NNAME00173     SMDAT_PCH_SLOT2                                          
P   NNAME00174     SMCLK_PCH_SLOT3                                          
P   NNAME00175     SMDAT_PCH_SLOT3                                          
P   NNAME00176     SMDAT_BMC_SLOT2                                          
P   NNAME00177     SMDAT_BMC_SLOT2_R                                        
P   NNAME00178     SMCLK_BMC_SLOT2                                          
P   NNAME00179     SMCLK_BMC_SLOT2_R                                        
P   NNAME00180     SMB_PCIE_SLOT2_ALERT_N                                   
P   NNAME00181     SMB_ALERT_S2_B12_N                                       
P   NNAME00182     SMDAT_PCH_SLOT2_R                                        
P   NNAME00183     SMCLK_PCH_SLOT2_R                                        
P   NNAME00184     SMDAT_BMC_SLOT3                                          
P   NNAME00185     SMDAT_BMC_SLOT3_R                                        
P   NNAME00186     SMCLK_BMC_SLOT3                                          
P   NNAME00187     SMCLK_BMC_SLOT3_R                                        
P   NNAME00188     SMB_PCIE_SLOT3_ALERT_N                                   
P   NNAME00189     SMB_ALERT_S3_B12_N                                       
P   NNAME00190     SMDAT_PCH_SLOT3_R                                        
P   NNAME00191     SMCLK_PCH_SLOT3_R                                        
P   NNAME00192     SMB_VMONITOR_SLOT2_MUX_SCL                               
P   NNAME00193     SMCLK_EXP_R_BMC                                          
P   NNAME00194     SMCLK_EXP_R_PCH                                          
P   NNAME00195     SMDAT_EXP_R_BMC                                          
P   NNAME00196     SMDAT_EXP_R_PCH                                          
P   NNAME00197     PU_I2CMUX_INT2_N                                         
P   NNAME00198     PD_SLOT2_PRSNT1                                          
P   NNAME00199     PD_SLOT3_PRSNT1                                          
P   NNAME00200     SMB_VMONITOR_SLOT2_MUX_SDA                               
P   NNAME00201     SLOT2_VMONITOR_A1                                        
P   NNAME00202     PU_P_I2CMUX_INT2_N                                       
P   NNAME00203     RESET_BUF_N_SLOT2                                        
P   NNAME00204     RESET_BUF_N_SLOT3                                        
P   NNAME00205     SLOT2_VMONITOR_A0                                        
P   NNAME00206     SMB_VMONITOR_SLOT3_MUX_SDA                               
P   NNAME00207     SMB_VMONITOR_SLOT3_MUX_SCL                               
P   NNAME00208     SLOT3_VMONITOR_A1                                        
P   NNAME00209     SLOT3_VMONITOR_A0                                        
P   NNAME00210     SMB_P_REPEATER_EN                                        
P   NNAME00211     SMCLK_USB_HUB_R                                          
P   NNAME00212     SMDAT_USB_HUB_R                                          
P   NNAME00213     USB_GF_HUB_DN_R                                          
P   NNAME00214     USB_GF_HUB_DP_R                                          
P   NNAME00215     SMB_U_REPEATER_EN                                        
P   NNAME00216     USB_HUB_PCIE_DP0                                         
P   NNAME00217     USB_HUB_PCIE_DN0                                         
P   NNAME00218     TP_RSVD_SLOT2_PIN82                                      
P   NNAME00219     USB_HUB_PCIE_DP1                                         
P   NNAME00220     USB_HUB_PCIE_DN1                                         
P   NNAME00221     TP_RSVD_SLOT3_PIN82                                      
327$NONE$                       D0040PA01X+010566Y+009887               S0      
327$NONE$                       D0040PA01X+010369Y+009887               S0      
327$NONE$                       D0040PA01X+010172Y+009887               S0      
327$NONE$                       D0040PA01X+010369Y+008666               S0      
327$NONE$                       D0040PA01X+010566Y+008666               S0      
327$NONE$                       D0040PA01X+010763Y+008666               S0      
327$NONE$                       D0040PA01X+041502Y+006000               S0      
327$NONE$                       D0040PA01X+041502Y+005212               S0      
327$NONE$                       D0040PA01X+041472Y+004819               S0      
327$NONE$                       D0040PA01X+042031Y+004486               S0      
327$NONE$                       D0040PA06X+044471Y-006431               S0      
327$NONE$                       D0040PA01X+052345Y-006431               S0      
327$NONE$                       D0040PA01X+052659Y-006431               S0      
327$NONE$                       D0040PA06X+052659Y-006431               S0      
327$NONE$                       D0040PA06X+052974Y-006431               S0      
327$NONE$                       D0040PA06X+053604Y-006431               S0      
317$NONE$                       D0040PA00X+013815Y+022811               S0      
317$NONE$                       D0040PA00X+014209Y+023598               S0      
317$NONE$                       D0040PA00X+020114Y+022811               S0      
317$NONE$                       D0040PA00X+032319Y+023598               S0      
317$NONE$                       D0040PA00X+015390Y+021827               S0      
317$NONE$                       D0040PA00X+016827Y+022319               S0      
317$NONE$                       D0040PA00X+045626Y+022319               S0      
327$NONE$                       D0040PA01X+052803Y+018072               S0      
327$NONE$                       D0040PA01X+052803Y+018269               S0      
327$NONE$                       D0040PA01X+052803Y+018466               S0      
327$NONE$                       D0040PA01X+051581Y+018269               S0      
327$NONE$                       D0040PA01X+051581Y+018072               S0      
327$NONE$                       D0040PA01X+051581Y+017875               S0      
327$NONE$                       D0040PA01X+013685Y-006391               S0      
327$NONE$                       D0040PA01X+014000Y-006391               S0      
327$NONE$                       D0040PA06X+014000Y-006391               S0      
327$NONE$                       D0040PA06X+014315Y-006391               S0      
327$NONE$                       D0040PA01X+014630Y-006391               S0      
327$NONE$                       D0040PA01X+014945Y-006391               S0      
327$NONE$                       D0040PA06X+014945Y-006391               S0      
327$NONE$                       D0040PA06X+015260Y-006391               S0      
327$NONE$                       D0040PA01X+017465Y-006391               S0      
327$NONE$                       D0040PA06X+019039Y-006391               S0      
327$NONE$                       D0040PA01X+008016Y+014639               S0      
327$NONE$                       D0040PA01X+007820Y+014639               S0      
327$NONE$                       D0040PA01X+007623Y+014639               S0      
327$NONE$                       D0040PA01X+007820Y+013418               S0      
327$NONE$                       D0040PA01X+008016Y+013418               S0      
327$NONE$                       D0040PA01X+008213Y+013418               S0      
317$NONE$                       D0040PA00X+013815Y+014811               S0      
317$NONE$                       D0040PA00X+014209Y+015598               S0      
317$NONE$                       D0040PA00X+020114Y+014811               S0      
317$NONE$                       D0040PA00X+032319Y+015598               S0      
317$NONE$                       D0040PA00X+015390Y+013827               S0      
317$NONE$                       D0040PA00X+016827Y+014319               S0      
317$NONE$                       D0040PA00X+045626Y+014319               S0      
317$NONE$                       D0040PA01X+003710Y+052413               S0      
317$NONE$                       D0040PA01X+004079Y+023068               S0      
317$NONE$                       D0040PA01X+054035Y+003275               S0      
317$NONE$                       D0040PA01X+057239Y+053229               S0      
317$NONE$                       D0040PA01X+059987Y+022946               S0      
317$NONE$                       D0040PA01X+060131Y-002692               S0      
317$NONE$                       D0040PA00X+001479Y+022631               S0      
317$NONE$                       D0040PA00X+054211Y+001743               S0      
317$NONE$                       D0040PA00X+058579Y+022887               S0      
317$NONE$           VIA        MD0040PA01X+061250Y+054080               S0      
317$NONE$           VIA        MD0040PA06X+061250Y+054080               S0      
317$NONE$           VIA        MD0040PA01X+002180Y-004150               S0      
317$NONE$           VIA        MD0040PA06X+002180Y-004150               S0      
317$NONE$           VIA        MD0040PA01X+061030Y-004360               S0      
317$NONE$           VIA        MD0040PA06X+061030Y-004360               S0      
317$NONE$           VIA        MD0040PA06X+059411Y-002651               S0      
317P12V_SLOT2                   D0040PA01X+009507Y+012139               S0      
317P12V_SLOT2                   D0040PA01X+009970Y+011330               S0      
317P12V_SLOT2                   D0040PA01X+008998Y+012133               S0      
317P12V_SLOT2                   D0040PA01X+004841Y+009765               S0      
317P12V_SLOT2                   D0040PA01X+004749Y+010569               S0      
327P12V_SLOT2                   D0040PA01X+007100Y+012010               S0      
317P12V_SLOT2                   D0040PA00X+012634Y+015598               S0      
317P12V_SLOT2                   D0040PA00X+013028Y+014811               S0      
317P12V_SLOT2                   D0040PA00X+012240Y+013827               S0      
317P12V_SLOT2                   D0040PA00X+012634Y+013039               S0      
317P12V_SLOT2                   D0040PA00X+013028Y+013827               S0      
317P12V_SLOT2                   D0040PA01X+009499Y+011328               S0      
317P12V_SLOT2       VIA        MD0040PA00X+005440Y+011000               S0      
317P12V_SLOT2       VIA        MD0040PA00X+005460Y+011490               S0      
317P12V_SLOT2       VIA        MD0040PA00X+005560Y+010510               S0      
317P12V_SLOT2       VIA        MD0040PA00X+005900Y+010790               S0      
317P12V_SLOT2       VIA        MD0040PA00X+005970Y+011520               S0      
317GND                          D0040PA01X+010330Y+001780               S0      
317GND                          D0040PA01X+046899Y+006010               S0      
317GND                          D0040PA01X+038010Y+003840               S0      
317GND                          D0040PA01X+015710Y+008440               S0      
327GND                          D0040PA01X+009857Y+009375               S0      
327GND                          D0040PA01X+010467Y+009276               S0      
317GND                          D0040PA01X+029260Y+019680               S0      
317GND                          D0040PA01X+024320Y+019730               S0      
317GND                          D0040PA01X+014660Y+008600               S0      
317GND                          D0040PA01X+036920Y+003540               S0      
317GND                          D0040PA01X+008955Y+022913               S0      
327GND                          D0040PA01X+011316Y+005945               S0      
317GND                          D0040PA01X+006340Y+015420               S0      
317GND                          D0040PA01X+033150Y+002820               S0      
327GND                          D0040PA01X+034464Y+003989               S0      
317GND                          D0040PA01X+009507Y+012699               S0      
317GND                          D0040PA01X+045099Y+007404               S0      
317GND                          D0040PA00X+054291Y+012815               S0      
317GND                          D0040PA01X+038380Y+000740               S0      
317GND                          D0040PA01X+009970Y+010770               S0      
317GND                          D0040PA01X+009070Y+009710               S0      
317GND                          D0040PA01X+010499Y+018348               S0      
327GND                          D0040PA01X+054822Y+023180               S0      
317GND                          D0040PA01X+053016Y+016250               S0      
317GND                          D0040PA01X+023420Y+019440               S0      
317GND                          D0040PA01X+009440Y+022901               S0      
317GND                          D0040PA01X+040136Y+005127               S0      
317GND                          D0040PA01X+052160Y+016240               S0      
317GND                          D0040PA01X+009809Y+013591               S0      
317GND                          D0040PA01X+009916Y+022902               S0      
317GND                          D0040PA01X+014660Y+007870               S0      
317GND                          D0040PA01X+019200Y+017790               S0      
317GND                          D0040PA01X+041230Y+003340               S0      
317GND                          D0040PA01X+011600Y+001790               S0      
317GND                          D0040PA01X+038000Y+006540               S0      
317GND                          D0040PA01X+037690Y+000740               S0      
327GND                          D0040PA01X+012034Y+006575               S0      
317GND                          D0040PA01X+005960Y+021050               S0      
327GND                          D0040PA01X+052443Y+023180               S0      
317GND                          D0040PA01X+010837Y+010533               S0      
327GND                          D0040PA01X+041502Y+006197               S0      
327GND                          D0040PA01X+042622Y+005606               S0      
317GND                          D0040PA01X+006530Y+014330               S0      
317GND                          D0040PA01X+008998Y+012693               S0      
317GND                          D0040PA01X+052430Y+019630               S0      
317GND                          D0040PA01X+014240Y+006670               S0      
317GND                          D0040PA01X+033280Y+005630               S0      
327GND                          D0040PA01X+034144Y+000289               S0      
327GND                          D0040PA01X+010300Y+019680               S0      
327GND                          D0040PA01X+044471Y-006431               S0      
327GND                          D0040PA06X+044785Y-006431               S0      
327GND                          D0040PA01X+045415Y-006431               S0      
327GND                          D0040PA06X+045730Y-006431               S0      
327GND                          D0040PA01X+046360Y-006431               S0      
327GND                          D0040PA06X+046675Y-006431               S0      
327GND                          D0040PA01X+047305Y-006431               S0      
327GND                          D0040PA06X+047620Y-006431               S0      
327GND                          D0040PA01X+048250Y-006431               S0      
327GND                          D0040PA06X+048565Y-006431               S0      
327GND                          D0040PA01X+049195Y-006431               S0      
327GND                          D0040PA06X+049510Y-006431               S0      
327GND                          D0040PA01X+050140Y-006431               S0      
327GND                          D0040PA06X+050455Y-006431               S0      
327GND                          D0040PA01X+051085Y-006431               S0      
327GND                          D0040PA06X+051400Y-006431               S0      
327GND                          D0040PA01X+052030Y-006431               S0      
327GND                          D0040PA06X+052345Y-006431               S0      
327GND                          D0040PA01X+052974Y-006431               S0      
327GND                          D0040PA06X+053289Y-006431               S0      
317GND                          D0040PA01X+010618Y+022662               S0      
317GND                          D0040PA01X+012120Y+008936               S0      
317GND                          D0040PA01X+045784Y+006011               S0      
327GND                          D0040PA01X+012180Y+017710               S0      
317GND                          D0040PA00X+013421Y+023598               S0      
317GND                          D0040PA00X+017358Y+023598               S0      
317GND                          D0040PA00X+018539Y+022811               S0      
317GND                          D0040PA00X+019720Y+023598               S0      
317GND                          D0040PA00X+020508Y+023598               S0      
317GND                          D0040PA00X+021689Y+022811               S0      
317GND                          D0040PA00X+022083Y+023598               S0      
317GND                          D0040PA00X+023264Y+022811               S0      
317GND                          D0040PA00X+023657Y+023598               S0      
317GND                          D0040PA00X+024839Y+022811               S0      
317GND                          D0040PA00X+026020Y+023598               S0      
317GND                          D0040PA00X+027201Y+022811               S0      
317GND                          D0040PA00X+027594Y+023598               S0      
317GND                          D0040PA00X+028776Y+022811               S0      
317GND                          D0040PA00X+029169Y+023598               S0      
317GND                          D0040PA00X+030350Y+022811               S0      
317GND                          D0040PA00X+030744Y+023598               S0      
317GND                          D0040PA00X+031925Y+022811               S0      
317GND                          D0040PA00X+032713Y+022811               S0      
317GND                          D0040PA00X+033894Y+023598               S0      
317GND                          D0040PA00X+034287Y+022811               S0      
317GND                          D0040PA00X+035468Y+023598               S0      
317GND                          D0040PA00X+035862Y+022811               S0      
317GND                          D0040PA00X+037043Y+023598               S0      
317GND                          D0040PA00X+037437Y+022811               S0      
317GND                          D0040PA00X+038618Y+023598               S0      
317GND                          D0040PA00X+039012Y+022811               S0      
317GND                          D0040PA00X+040193Y+023598               S0      
317GND                          D0040PA00X+040587Y+022811               S0      
317GND                          D0040PA00X+041768Y+023598               S0      
317GND                          D0040PA00X+042161Y+022811               S0      
317GND                          D0040PA00X+043342Y+023598               S0      
317GND                          D0040PA00X+043736Y+022811               S0      
317GND                          D0040PA00X+044917Y+023598               S0      
317GND                          D0040PA00X+013421Y+021039               S0      
317GND                          D0040PA00X+014602Y+021827               S0      
317GND                          D0040PA00X+017752Y+021827               S0      
317GND                          D0040PA00X+018933Y+021039               S0      
317GND                          D0040PA00X+019720Y+021039               S0      
317GND                          D0040PA00X+020902Y+021827               S0      
317GND                          D0040PA00X+021295Y+021039               S0      
317GND                          D0040PA00X+022476Y+021827               S0      
317GND                          D0040PA00X+022870Y+021039               S0      
317GND                          D0040PA00X+024051Y+021827               S0      
317GND                          D0040PA00X+025232Y+021039               S0      
317GND                          D0040PA00X+026413Y+021827               S0      
317GND                          D0040PA00X+026807Y+021039               S0      
317GND                          D0040PA00X+027988Y+021827               S0      
317GND                          D0040PA00X+028382Y+021039               S0      
317GND                          D0040PA00X+029563Y+021827               S0      
317GND                          D0040PA00X+029957Y+021039               S0      
317GND                          D0040PA00X+031138Y+021827               S0      
317GND                          D0040PA00X+031925Y+021827               S0      
317GND                          D0040PA00X+033106Y+021039               S0      
317GND                          D0040PA00X+033500Y+021827               S0      
317GND                          D0040PA00X+034681Y+021039               S0      
317GND                          D0040PA00X+035075Y+021827               S0      
317GND                          D0040PA00X+036256Y+021039               S0      
317GND                          D0040PA00X+036650Y+021827               S0      
317GND                          D0040PA00X+037831Y+021039               S0      
317GND                          D0040PA00X+038224Y+021827               S0      
317GND                          D0040PA00X+039405Y+021039               S0      
317GND                          D0040PA00X+039799Y+021827               S0      
317GND                          D0040PA00X+040980Y+021039               S0      
317GND                          D0040PA00X+041374Y+021827               S0      
317GND                          D0040PA00X+042555Y+021039               S0      
317GND                          D0040PA00X+042949Y+021827               S0      
317GND                          D0040PA00X+044130Y+021039               S0      
317GND                          D0040PA01X+037709Y+001737               S0      
317GND                          D0040PA01X+041880Y+003070               S0      
317GND                          D0040PA01X+040130Y+005487               S0      
317GND                          D0040PA01X+016030Y+006640               S0      
317GND                          D0040PA01X+008800Y+009120               S0      
317GND                          D0040PA01X+038021Y+005557               S0      
317GND                          D0040PA01X+016340Y+018380               S0      
317GND                          D0040PA01X+038680Y+005550               S0      
327GND                          D0040PA01X+054029Y+023180               S0      
317GND                          D0040PA01X+014660Y+008240               S0      
317GND                          D0040PA01X+045400Y+004430               S0      
327GND                          D0040PA01X+008924Y+017364               S0      
317GND                          D0040PA01X+045140Y+007838               S0      
317GND                          D0040PA01X+038370Y+002170               S0      
327GND                          D0040PA01X+020578Y+017241               S0      
317GND                          D0040PA01X+045800Y+003710               S0      
327GND                          D0040PA01X+052290Y+018781               S0      
327GND                          D0040PA01X+052192Y+018170               S0      
327GND                          D0040PA01X+002530Y+019590               S0      
317GND                          D0040PA01X+042987Y+003064               S0      
317GND                          D0040PA01X+040433Y+000082               S0      
317GND                          D0040PA01X+005590Y+017680               S0      
317GND                          D0040PA01X+037710Y+002150               S0      
317GND                          D0040PA01X+013310Y+005980               S0      
317GND                          D0040PA01X+008463Y+022914               S0      
317GND                          D0040PA00X+056102Y+020679               S0      
317GND                          D0040PA00X+056102Y+019026               S0      
317GND                          D0040PA01X+038370Y+001730               S0      
317GND                          D0040PA00X+001575Y+012815               S0      
317GND                          D0040PA01X+010507Y+018731               S0      
317GND                          D0040PA01X+033280Y+006040               S0      
327GND                          D0040PA01X+009591Y-006391               S0      
327GND                          D0040PA06X+009591Y-006391               S0      
327GND                          D0040PA06X+011480Y-006391               S0      
327GND                          D0040PA01X+012425Y-006391               S0      
327GND                          D0040PA06X+012740Y-006391               S0      
327GND                          D0040PA01X+013370Y-006391               S0      
327GND                          D0040PA06X+013685Y-006391               S0      
327GND                          D0040PA01X+014315Y-006391               S0      
327GND                          D0040PA06X+014630Y-006391               S0      
327GND                          D0040PA01X+015260Y-006391               S0      
327GND                          D0040PA06X+015575Y-006391               S0      
327GND                          D0040PA01X+016205Y-006391               S0      
327GND                          D0040PA06X+016520Y-006391               S0      
327GND                          D0040PA01X+017150Y-006391               S0      
327GND                          D0040PA06X+017465Y-006391               S0      
327GND                          D0040PA01X+019039Y-006391               S0      
327GND                          D0040PA06X+019354Y-006391               S0      
327GND                          D0040PA01X+019984Y-006391               S0      
327GND                          D0040PA06X+020299Y-006391               S0      
327GND                          D0040PA01X+020929Y-006391               S0      
327GND                          D0040PA06X+021244Y-006391               S0      
327GND                          D0040PA01X+021874Y-006391               S0      
327GND                          D0040PA06X+022189Y-006391               S0      
327GND                          D0040PA01X+022819Y-006391               S0      
327GND                          D0040PA06X+023134Y-006391               S0      
327GND                          D0040PA01X+023764Y-006391               S0      
327GND                          D0040PA06X+024079Y-006391               S0      
327GND                          D0040PA01X+024709Y-006391               S0      
327GND                          D0040PA06X+025024Y-006391               S0      
327GND                          D0040PA01X+025654Y-006391               S0      
327GND                          D0040PA06X+025969Y-006391               S0      
327GND                          D0040PA01X+026599Y-006391               S0      
327GND                          D0040PA06X+026913Y-006391               S0      
327GND                          D0040PA01X+027543Y-006391               S0      
327GND                          D0040PA06X+027858Y-006391               S0      
327GND                          D0040PA01X+028488Y-006391               S0      
327GND                          D0040PA06X+028803Y-006391               S0      
327GND                          D0040PA01X+029433Y-006391               S0      
327GND                          D0040PA06X+029748Y-006391               S0      
327GND                          D0040PA01X+030378Y-006391               S0      
327GND                          D0040PA06X+030693Y-006391               S0      
327GND                          D0040PA01X+031323Y-006391               S0      
327GND                          D0040PA06X+031638Y-006391               S0      
327GND                          D0040PA01X+032268Y-006391               S0      
327GND                          D0040PA06X+032583Y-006391               S0      
327GND                          D0040PA01X+033213Y-006391               S0      
327GND                          D0040PA06X+033528Y-006391               S0      
327GND                          D0040PA01X+034157Y-006391               S0      
327GND                          D0040PA06X+034473Y-006391               S0      
327GND                          D0040PA01X+035102Y-006391               S0      
327GND                          D0040PA06X+035417Y-006391               S0      
327GND                          D0040PA01X+036047Y-006391               S0      
327GND                          D0040PA06X+036362Y-006391               S0      
327GND                          D0040PA01X+036992Y-006391               S0      
327GND                          D0040PA06X+037307Y-006391               S0      
327GND                          D0040PA01X+037937Y-006391               S0      
327GND                          D0040PA06X+038252Y-006391               S0      
327GND                          D0040PA01X+038882Y-006391               S0      
327GND                          D0040PA06X+039197Y-006391               S0      
327GND                          D0040PA01X+039827Y-006391               S0      
327GND                          D0040PA06X+040142Y-006391               S0      
317GND                          D0040PA01X+052060Y+020020               S0      
317GND                          D0040PA01X+016750Y+018600               S0      
327GND                          D0040PA01X+045916Y+007207               S0      
327GND                          D0040PA01X+046838Y+006611               S0      
317GND                          D0040PA01X+024640Y+018490               S0      
317GND                          D0040PA01X+043523Y+008430               S0      
317GND                          D0040PA01X+043363Y+008871               S0      
317GND                          D0040PA01X+032700Y+002390               S0      
317GND                          D0040PA01X+008540Y+004840               S0      
317GND                          D0040PA01X+041145Y+000240               S0      
317GND                          D0040PA01X+016700Y+010790               S0      
327GND                          D0040PA01X+039465Y+002859               S0      
317GND                          D0040PA01X+036020Y-000180               S0      
317GND                          D0040PA01X+038680Y+005070               S0      
317GND                          D0040PA01X+042692Y+003462               S0      
317GND                          D0040PA01X+005630Y+017240               S0      
327GND                          D0040PA01X+053236Y+023180               S0      
327GND                          D0040PA01X+015410Y+010300               S0      
317GND                          D0040PA01X+006200Y+013940               S0      
317GND                          D0040PA01X+045243Y+006018               S0      
327GND                          D0040PA01X+007070Y+008200               S0      
317GND                          D0040PA01X+038020Y+005070               S0      
327GND                          D0040PA01X+025994Y+017346               S0      
317GND                          D0040PA01X+010250Y+006940               S0      
327GND                          D0040PA01X+007100Y+010090               S0      
317GND                          D0040PA01X+016070Y+006230               S0      
327GND                          D0040PA01X+007307Y+014127               S0      
327GND                          D0040PA01X+007918Y+014029               S0      
317GND                          D0040PA01X+038690Y+006540               S0      
317GND                          D0040PA01X+040436Y+006561               S0      
317GND                          D0040PA00X+013421Y+015598               S0      
317GND                          D0040PA00X+017358Y+015598               S0      
317GND                          D0040PA00X+018539Y+014811               S0      
317GND                          D0040PA00X+019720Y+015598               S0      
317GND                          D0040PA00X+020508Y+015598               S0      
317GND                          D0040PA00X+021689Y+014811               S0      
317GND                          D0040PA00X+022083Y+015598               S0      
317GND                          D0040PA00X+023264Y+014811               S0      
317GND                          D0040PA00X+023657Y+015598               S0      
317GND                          D0040PA00X+024839Y+014811               S0      
317GND                          D0040PA00X+026020Y+015598               S0      
317GND                          D0040PA00X+027201Y+014811               S0      
317GND                          D0040PA00X+027594Y+015598               S0      
317GND                          D0040PA00X+028776Y+014811               S0      
317GND                          D0040PA00X+029169Y+015598               S0      
317GND                          D0040PA00X+030350Y+014811               S0      
317GND                          D0040PA00X+030744Y+015598               S0      
317GND                          D0040PA00X+031925Y+014811               S0      
317GND                          D0040PA00X+032713Y+014811               S0      
317GND                          D0040PA00X+033894Y+015598               S0      
317GND                          D0040PA00X+034287Y+014811               S0      
317GND                          D0040PA00X+035468Y+015598               S0      
317GND                          D0040PA00X+035862Y+014811               S0      
317GND                          D0040PA00X+037043Y+015598               S0      
317GND                          D0040PA00X+037437Y+014811               S0      
317GND                          D0040PA00X+038618Y+015598               S0      
317GND                          D0040PA00X+039012Y+014811               S0      
317GND                          D0040PA00X+040193Y+015598               S0      
317GND                          D0040PA00X+040587Y+014811               S0      
317GND                          D0040PA00X+041768Y+015598               S0      
317GND                          D0040PA00X+042161Y+014811               S0      
317GND                          D0040PA00X+043342Y+015598               S0      
317GND                          D0040PA00X+043736Y+014811               S0      
317GND                          D0040PA00X+044917Y+015598               S0      
317GND                          D0040PA00X+013421Y+013039               S0      
317GND                          D0040PA00X+014602Y+013827               S0      
317GND                          D0040PA00X+017752Y+013827               S0      
317GND                          D0040PA00X+018933Y+013039               S0      
317GND                          D0040PA00X+019720Y+013039               S0      
317GND                          D0040PA00X+020902Y+013827               S0      
317GND                          D0040PA00X+021295Y+013039               S0      
317GND                          D0040PA00X+022476Y+013827               S0      
317GND                          D0040PA00X+022870Y+013039               S0      
317GND                          D0040PA00X+024051Y+013827               S0      
317GND                          D0040PA00X+025232Y+013039               S0      
317GND                          D0040PA00X+026413Y+013827               S0      
317GND                          D0040PA00X+026807Y+013039               S0      
317GND                          D0040PA00X+027988Y+013827               S0      
317GND                          D0040PA00X+028382Y+013039               S0      
317GND                          D0040PA00X+029563Y+013827               S0      
317GND                          D0040PA00X+029957Y+013039               S0      
317GND                          D0040PA00X+031138Y+013827               S0      
317GND                          D0040PA00X+031925Y+013827               S0      
317GND                          D0040PA00X+033106Y+013039               S0      
317GND                          D0040PA00X+033500Y+013827               S0      
317GND                          D0040PA00X+034681Y+013039               S0      
317GND                          D0040PA00X+035075Y+013827               S0      
317GND                          D0040PA00X+036256Y+013039               S0      
317GND                          D0040PA00X+036650Y+013827               S0      
317GND                          D0040PA00X+037831Y+013039               S0      
317GND                          D0040PA00X+038224Y+013827               S0      
317GND                          D0040PA00X+039405Y+013039               S0      
317GND                          D0040PA00X+039799Y+013827               S0      
317GND                          D0040PA00X+040980Y+013039               S0      
317GND                          D0040PA00X+041374Y+013827               S0      
317GND                          D0040PA00X+042555Y+013039               S0      
317GND                          D0040PA00X+042949Y+013827               S0      
317GND                          D0040PA00X+044130Y+013039               S0      
317GND                          D0040PA01X+016580Y+010380               S0      
317GND                          D0040PA01X+036320Y+007250               S0      
317GND                          D0040PA01X+045166Y+006654               S0      
317GND                          D0040PA01X+009570Y+017980               S0      
317GND                          D0040PA01X+009499Y+010768               S0      
317GND                          D0040PA01X+009809Y+014004               S0      
327GND                          D0040PA01X+015059Y-000004               S0      
327GND                          D0040PA01X+015571Y+000736               S0      
317GND                          D0040PA01X+045112Y+003331               S0      
317GND                          D0040PA01X+043942Y+002964               S0      
317GND                          D0040PA01X+010507Y+019085               S0      
327GND                          D0040PA06X+005156Y+007138               S0      
317GND                          D0040PA06X+006112Y+007088               S0      
317GND                          D0040PA06X+006244Y+007452               S0      
317GND                          D0040PA06X+006244Y+007295               S0      
317GND                          D0040PA06X+006244Y+007138               S0      
317GND                          D0040PA06X+006244Y+006980               S0      
317GND                          D0040PA06X+006244Y+006823               S0      
317GND                          D0040PA06X+006244Y+006665               S0      
317GND                          D0040PA06X+006244Y+006508               S0      
317GND                          D0040PA06X+003090Y+006005               S0      
317GND                          D0040PA06X+004897Y+005618               S0      
327GND                          D0040PA06X+007740Y+004950               S0      
327GND                          D0040PA06X+007030Y+008560               S0      
317GND                          D0040PA06X+007080Y+006570               S0      
317GND                          D0040PA06X+003650Y+007490               S0      
327GND                          D0040PA06X+008510Y+004950               S0      
317GND                          D0040PA06X+004480Y+008520               S0      
317GND                          D0040PA06X+004450Y+007080               S0      
327GND                          D0040PA06X+008510Y+002310               S0      
317GND                          D0040PA06X+004300Y+008070               S0      
327GND                          D0040PA06X+007740Y+002310               S0      
317GND              VIA        MD0040PA06X+034210Y+017920               S0      
317GND              VIA        MD0040PA06X+042660Y-002040               S0      
317GND              VIA        MD0040PA06X+004340Y+019170               S0      
317GND              VIA        MD0040PA06X+050760Y+020440               S0      
317GND              VIA        MD0040PA06X+052300Y+006870               S0      
317GND              VIA        MD0040PA06X+052420Y+016780               S0      
317GND              VIA        MD0040PA06X+058980Y+020090               S0      
317GND              VIA        MD0040PA06X+007660Y+008570               S0      
317GND              VIA        MD0040PA01X+001210Y+018090               S0      
317GND              VIA        MD0040PA01X+002800Y+021650               S0      
317GND              VIA        MD0040PA01X+047680Y+022230               S0      
317GND              VIA        MD0040PA01X+050830Y+022990               S0      
317GND              VIA        MD0040PA01X+052445Y+007150               S0      
317GND              VIA        MD0040PA00X+010070Y+018290               S0      
317GND              VIA        MD0040PA00X+010070Y+018630               S0      
317GND              VIA        MD0040PA00X+010080Y+018970               S0      
317GND              VIA        MD0040PA00X+010150Y+013591               S0      
317GND              VIA        MD0040PA00X+010474Y+017495               S0      
317GND              VIA        MD0040PA00X+011610Y+016970               S0      
317GND              VIA        MD0040PA00X+011690Y-003540               S0      
317GND              VIA        MD0040PA00X+011690Y+005945               S0      
317GND              VIA        MD0040PA00X+011720Y+006575               S0      
317GND              VIA        MD0040PA00X+012040Y+016980               S0      
317GND              VIA        MD0040PA00X+012180Y+001700               S0      
317GND              VIA        MD0040PA00X+012490Y+008890               S0      
317GND              VIA        MD0040PA00X+012530Y+017020               S0      
317GND              VIA        MD0040PA00X+012680Y-005341               S0      
317GND              VIA        MD0040PA00X+013260Y+003990               S0      
317GND              VIA        MD0040PA00X+013400Y+006340               S0      
317GND              VIA        MD0040PA00X+013518Y-005341               S0      
317GND              VIA        MD0040PA00X+014463Y-005341               S0      
317GND              VIA        MD0040PA00X+014660Y+000340               S0      
317GND              VIA        MD0040PA00X+014895Y+010960               S0      
317GND              VIA        MD0040PA00X+001495Y+016597               S0      
317GND              VIA        MD0040PA00X+001495Y+017597               S0      
317GND              VIA        MD0040PA00X+001495Y+018597               S0      
317GND              VIA        MD0040PA00X+001495Y+019597               S0      
317GND              VIA        MD0040PA00X+015115Y+008350               S0      
317GND              VIA        MD0040PA00X+015155Y+008750               S0      
317GND              VIA        MD0040PA00X+015265Y+010980               S0      
317GND              VIA        MD0040PA00X+001545Y+023587               S0      
317GND              VIA        MD0040PA00X+015408Y-005341               S0      
317GND              VIA        MD0040PA00X+015660Y+010980               S0      
317GND              VIA        MD0040PA00X+015945Y+000875               S0      
317GND              VIA        MD0040PA00X+015945Y+009740               S0      
317GND              VIA        MD0040PA00X+016110Y+001360               S0      
317GND              VIA        MD0040PA00X+016180Y+007110               S0      
317GND              VIA        MD0040PA00X+016353Y-005341               S0      
317GND              VIA        MD0040PA00X+017298Y-005341               S0      
317GND              VIA        MD0040PA00X+017440Y+003250               S0      
317GND              VIA        MD0040PA00X+017630Y+004520               S0      
317GND              VIA        MD0040PA00X+018200Y+006670               S0      
317GND              VIA        MD0040PA00X+019188Y-005341               S0      
317GND              VIA        MD0040PA00X+019390Y+005160               S0      
317GND              VIA        MD0040PA00X+019520Y+000570               S0      
317GND              VIA        MD0040PA00X+019640Y+009160               S0      
317GND              VIA        MD0040PA00X+019685Y+017795               S0      
317GND              VIA        MD0040PA00X+019830Y+007320               S0      
317GND              VIA        MD0040PA00X+019890Y+002120               S0      
317GND              VIA        MD0040PA00X+020050Y+003150               S0      
317GND              VIA        MD0040PA00X+020132Y-005341               S0      
317GND              VIA        MD0040PA00X+020230Y+016510               S0      
317GND              VIA        MD0040PA00X+020280Y+005020               S0      
317GND              VIA        MD0040PA00X+021077Y-005341               S0      
317GND              VIA        MD0040PA00X+021630Y+004670               S0      
317GND              VIA        MD0040PA00X+021890Y+006560               S0      
317GND              VIA        MD0040PA00X+022022Y-005341               S0      
317GND              VIA        MD0040PA00X+022190Y+000510               S0      
317GND              VIA        MD0040PA00X+022660Y+002140               S0      
317GND              VIA        MD0040PA00X+002270Y+019080               S0      
317GND              VIA        MD0040PA00X+022967Y-005341               S0      
317GND              VIA        MD0040PA00X+002300Y+020100               S0      
317GND              VIA        MD0040PA00X+023030Y+004510               S0      
317GND              VIA        MD0040PA00X+023380Y+006600               S0      
317GND              VIA        MD0040PA00X+023560Y+000530               S0      
317GND              VIA        MD0040PA00X+023912Y-005341               S0      
317GND              VIA        MD0040PA00X+023940Y+019150               S0      
317GND              VIA        MD0040PA00X+024010Y+002090               S0      
317GND              VIA        MD0040PA00X+024280Y+020060               S0      
317GND              VIA        MD0040PA00X+024300Y+018530               S0      
317GND              VIA        MD0040PA00X+024650Y+004790               S0      
317GND              VIA        MD0040PA00X+024720Y+000540               S0      
317GND              VIA        MD0040PA00X+024857Y-005341               S0      
317GND              VIA        MD0040PA00X+025230Y+002220               S0      
317GND              VIA        MD0040PA00X+002545Y+023587               S0      
317GND              VIA        MD0040PA00X+025590Y+003500               S0      
317GND              VIA        MD0040PA00X+025802Y-005341               S0      
317GND              VIA        MD0040PA00X+026240Y+016990               S0      
317GND              VIA        MD0040PA00X+002630Y+019080               S0      
317GND              VIA        MD0040PA00X+002660Y+020100               S0      
317GND              VIA        MD0040PA00X+026747Y-005341               S0      
317GND              VIA        MD0040PA00X+027691Y-005341               S0      
317GND              VIA        MD0040PA00X+028636Y-005341               S0      
317GND              VIA        MD0040PA00X+029580Y+019590               S0      
317GND              VIA        MD0040PA00X+029581Y-005341               S0      
317GND              VIA        MD0040PA00X+030526Y-005341               S0      
317GND              VIA        MD0040PA00X+003070Y+005640               S0      
317GND              VIA        MD0040PA00X+031471Y-005341               S0      
317GND              VIA        MD0040PA00X+031907Y-004154               S0      
317GND              VIA        MD0040PA00X+032416Y-005341               S0      
317GND              VIA        MD0040PA00X+032464Y-004148               S0      
317GND              VIA        MD0040PA00X+032660Y+018200               S0      
317GND              VIA        MD0040PA00X+032800Y+003050               S0      
317GND              VIA        MD0040PA00X+032800Y+005900               S0      
317GND              VIA        MD0040PA00X+032866Y+017095               S0      
317GND              VIA        MD0040PA00X+032974Y-004148               S0      
317GND              VIA        MD0040PA00X+033361Y-005341               S0      
317GND              VIA        MD0040PA00X+033484Y-004148               S0      
317GND              VIA        MD0040PA00X+033965Y+004154               S0      
317GND              VIA        MD0040PA00X+033994Y-004148               S0      
317GND              VIA        MD0040PA00X+034306Y-005341               S0      
317GND              VIA        MD0040PA00X+034504Y-004148               S0      
317GND              VIA        MD0040PA00X+035014Y-004148               S0      
317GND              VIA        MD0040PA00X+035251Y-005341               S0      
317GND              VIA        MD0040PA00X+035260Y+000760               S0      
317GND              VIA        MD0040PA00X+003545Y+023587               S0      
317GND              VIA        MD0040PA00X+035524Y-004148               S0      
317GND              VIA        MD0040PA00X+036034Y-004148               S0      
317GND              VIA        MD0040PA00X+036160Y+006910               S0      
317GND              VIA        MD0040PA00X+036195Y-005341               S0      
317GND              VIA        MD0040PA00X+036544Y-004148               S0      
317GND              VIA        MD0040PA00X+037040Y+008820               S0      
317GND              VIA        MD0040PA00X+037054Y-004148               S0      
317GND              VIA        MD0040PA00X+037140Y-005341               S0      
317GND              VIA        MD0040PA00X+037330Y+003540               S0      
317GND              VIA        MD0040PA00X+037564Y-004148               S0      
317GND              VIA        MD0040PA00X+037780Y+008780               S0      
317GND              VIA        MD0040PA00X+038020Y+000680               S0      
317GND              VIA        MD0040PA00X+038030Y+002160               S0      
317GND              VIA        MD0040PA00X+038050Y+001710               S0      
317GND              VIA        MD0040PA00X+038074Y-004148               S0      
317GND              VIA        MD0040PA00X+038085Y-005341               S0      
317GND              VIA        MD0040PA00X+038330Y+005070               S0      
317GND              VIA        MD0040PA00X+038350Y+006580               S0      
317GND              VIA        MD0040PA00X+038360Y+005553               S0      
317GND              VIA        MD0040PA00X+038400Y+004160               S0      
317GND              VIA        MD0040PA00X+038584Y-004148               S0      
317GND              VIA        MD0040PA00X+038800Y+004160               S0      
317GND              VIA        MD0040PA00X+039030Y-005341               S0      
317GND              VIA        MD0040PA00X+039094Y-004148               S0      
317GND              VIA        MD0040PA00X+039160Y+002940               S0      
317GND              VIA        MD0040PA00X+039450Y+003400               S0      
317GND              VIA        MD0040PA00X+039604Y-004148               S0      
317GND              VIA        MD0040PA00X+003990Y+007280               S0      
317GND              VIA        MD0040PA00X+039982Y-005274               S0      
317GND              VIA        MD0040PA00X+040114Y-004148               S0      
317GND              VIA        MD0040PA00X+040121Y+004659               S0      
317GND              VIA        MD0040PA00X+040550Y+002920               S0      
317GND              VIA        MD0040PA00X+040557Y+007273               S0      
317GND              VIA        MD0040PA00X+040560Y+008750               S0      
317GND              VIA        MD0040PA00X+040580Y+002110               S0      
317GND              VIA        MD0040PA00X+040580Y+009420               S0      
317GND              VIA        MD0040PA00X+040903Y+006121               S0      
317GND              VIA        MD0040PA00X+041005Y-003683               S0      
317GND              VIA        MD0040PA00X+041510Y+000340               S0      
317GND              VIA        MD0040PA00X+041630Y+003710               S0      
317GND              VIA        MD0040PA00X+041871Y+003470               S0      
317GND              VIA        MD0040PA00X+042025Y-003692               S0      
317GND              VIA        MD0040PA00X+042350Y+003420               S0      
317GND              VIA        MD0040PA00X+042385Y+000438               S0      
317GND              VIA        MD0040PA00X+043138Y+003528               S0      
317GND              VIA        MD0040PA00X+043245Y-003623               S0      
317GND              VIA        MD0040PA00X+043675Y+000418               S0      
317GND              VIA        MD0040PA00X+043730Y+009110               S0      
317GND              VIA        MD0040PA00X+043942Y+002611               S0      
317GND              VIA        MD0040PA00X+044525Y-003722               S0      
317GND              VIA        MD0040PA00X+044625Y-005343               S0      
317GND              VIA        MD0040PA00X+044725Y-004772               S0      
317GND              VIA        MD0040PA00X+044820Y+009300               S0      
317GND              VIA        MD0040PA00X+044837Y+008663               S0      
317GND              VIA        MD0040PA00X+004520Y+008940               S0      
317GND              VIA        MD0040PA00X+045250Y+007010               S0      
317GND              VIA        MD0040PA00X+045289Y+010844               S0      
317GND              VIA        MD0040PA00X+004545Y+023587               S0      
317GND              VIA        MD0040PA00X+045409Y+006327               S0      
317GND              VIA        MD0040PA00X+045450Y+002930               S0      
317GND              VIA        MD0040PA00X+045570Y-005343               S0      
317GND              VIA        MD0040PA00X+045710Y+010855               S0      
317GND              VIA        MD0040PA00X+045740Y+004180               S0      
317GND              VIA        MD0040PA00X+004580Y+005480               S0      
317GND              VIA        MD0040PA00X+045810Y+004730               S0      
317GND              VIA        MD0040PA00X+045810Y+005370               S0      
317GND              VIA        MD0040PA00X+045965Y+003157               S0      
317GND              VIA        MD0040PA00X+046515Y-005343               S0      
317GND              VIA        MD0040PA00X+046601Y+021633               S0      
317GND              VIA        MD0040PA00X+046636Y+023094               S0      
317GND              VIA        MD0040PA00X+046751Y+022611               S0      
317GND              VIA        MD0040PA00X+046859Y+005598               S0      
317GND              VIA        MD0040PA00X+046930Y+008760               S0      
317GND              VIA        MD0040PA00X+047460Y-005343               S0      
317GND              VIA        MD0040PA00X+047976Y+023634               S0      
317GND              VIA        MD0040PA00X+048076Y+022794               S0      
317GND              VIA        MD0040PA00X+048405Y-005343               S0      
317GND              VIA        MD0040PA00X+048816Y+023634               S0      
317GND              VIA        MD0040PA00X+048865Y-001823               S0      
317GND              VIA        MD0040PA00X+049020Y-000640               S0      
317GND              VIA        MD0040PA00X+049296Y+022734               S0      
317GND              VIA        MD0040PA00X+049350Y-005343               S0      
317GND              VIA        MD0040PA00X+049635Y-001903               S0      
317GND              VIA        MD0040PA00X+049805Y-000063               S0      
317GND              VIA        MD0040PA00X+049976Y+023634               S0      
317GND              VIA        MD0040PA00X+050200Y+022940               S0      
317GND              VIA        MD0040PA00X+050295Y-005343               S0      
317GND              VIA        MD0040PA00X+050596Y+023694               S0      
317GND              VIA        MD0040PA00X+051190Y+014270               S0      
317GND              VIA        MD0040PA00X+051190Y+017440               S0      
317GND              VIA        MD0040PA00X+051200Y+015840               S0      
317GND              VIA        MD0040PA00X+051239Y-005343               S0      
317GND              VIA        MD0040PA00X+051976Y+023634               S0      
317GND              VIA        MD0040PA00X+052160Y+015840               S0      
317GND              VIA        MD0040PA00X+052184Y-005343               S0      
317GND              VIA        MD0040PA00X+052330Y-003210               S0      
317GND              VIA        MD0040PA00X+052400Y+020000               S0      
317GND              VIA        MD0040PA00X+052859Y-001224               S0      
317GND              VIA        MD0040PA00X+052859Y+000276               S0      
317GND              VIA        MD0040PA00X+052900Y+015850               S0      
317GND              VIA        MD0040PA00X+052950Y+023640               S0      
317GND              VIA        MD0040PA00X+053129Y-005343               S0      
317GND              VIA        MD0040PA00X+053160Y-003180               S0      
317GND              VIA        MD0040PA00X+053214Y+000789               S0      
317GND              VIA        MD0040PA00X+053269Y-001773               S0      
317GND              VIA        MD0040PA00X+053278Y+002174               S0      
317GND              VIA        MD0040PA00X+053434Y+005279               S0      
317GND              VIA        MD0040PA00X+053464Y+007429               S0      
317GND              VIA        MD0040PA00X+053464Y+009259               S0      
317GND              VIA        MD0040PA00X+053474Y+004029               S0      
317GND              VIA        MD0040PA00X+053720Y+023640               S0      
317GND              VIA        MD0040PA00X+054530Y+023680               S0      
317GND              VIA        MD0040PA00X+054820Y+016990               S0      
317GND              VIA        MD0040PA00X+054830Y+017810               S0      
317GND              VIA        MD0040PA00X+005545Y+023587               S0      
317GND              VIA        MD0040PA00X+055976Y+023634               S0      
317GND              VIA        MD0040PA00X+005630Y+018000               S0      
317GND              VIA        MD0040PA00X+057775Y+018111               S0      
317GND              VIA        MD0040PA00X+057775Y+019111               S0      
317GND              VIA        MD0040PA00X+057775Y+020111               S0      
317GND              VIA        MD0040PA00X+057775Y+021111               S0      
317GND              VIA        MD0040PA00X+057834Y+016689               S0      
317GND              VIA        MD0040PA00X+057834Y+022689               S0      
317GND              VIA        MD0040PA00X+057976Y+023634               S0      
317GND              VIA        MD0040PA00X+059334Y+016689               S0      
317GND              VIA        MD0040PA00X+059334Y+017689               S0      
317GND              VIA        MD0040PA00X+059334Y+018689               S0      
317GND              VIA        MD0040PA00X+059334Y+019689               S0      
317GND              VIA        MD0040PA00X+059334Y+020689               S0      
317GND              VIA        MD0040PA00X+059334Y+021689               S0      
317GND              VIA        MD0040PA00X+059334Y+022689               S0      
317GND              VIA        MD0040PA00X+005960Y+021400               S0      
317GND              VIA        MD0040PA00X+059976Y+023634               S0      
317GND              VIA        MD0040PA00X+060834Y+016689               S0      
317GND              VIA        MD0040PA00X+060834Y+017689               S0      
317GND              VIA        MD0040PA00X+060834Y+018689               S0      
317GND              VIA        MD0040PA00X+060834Y+019689               S0      
317GND              VIA        MD0040PA00X+060834Y+020689               S0      
317GND              VIA        MD0040PA00X+060834Y+021689               S0      
317GND              VIA        MD0040PA00X+060834Y+022689               S0      
317GND              VIA        MD0040PA00X+006200Y+014290               S0      
317GND              VIA        MD0040PA00X+006270Y+015010               S0      
317GND              VIA        MD0040PA00X+000649Y+016576               S0      
317GND              VIA        MD0040PA00X+000649Y+017576               S0      
317GND              VIA        MD0040PA00X+000649Y+018576               S0      
317GND              VIA        MD0040PA00X+000649Y+019576               S0      
317GND              VIA        MD0040PA00X+000649Y+020576               S0      
317GND              VIA        MD0040PA00X+000649Y+021576               S0      
317GND              VIA        MD0040PA00X+000649Y+022576               S0      
317GND              VIA        MD0040PA00X+000649Y+023576               S0      
317GND              VIA        MD0040PA00X+006545Y+023587               S0      
317GND              VIA        MD0040PA00X+006900Y+014330               S0      
317GND              VIA        MD0040PA00X+007545Y+023587               S0      
317GND              VIA        MD0040PA00X+008170Y+012970               S0      
317GND              VIA        MD0040PA00X+008180Y+012590               S0      
317GND              VIA        MD0040PA00X+008440Y+023290               S0      
317GND              VIA        MD0040PA00X+008570Y+012990               S0      
317GND              VIA        MD0040PA00X+008590Y+012630               S0      
317GND              VIA        MD0040PA00X+008960Y+023290               S0      
317GND              VIA        MD0040PA00X+009294Y+000663               S0      
317GND              VIA        MD0040PA00X+009390Y+009530               S0      
317GND              VIA        MD0040PA00X+009490Y+023300               S0      
317GND              VIA        MD0040PA00X+009830Y+007200               S0      
317GND              VIA        MD0040PA00X+009840Y+023310               S0      
317GND              VIA        MD0040PA00X+009890Y+012680               S0      
317GND              VIA        MD0040PA00X+009900Y+001380               S0      
317GND              VIA        MD0040PA00X+009920Y+001810               S0      
317GND              VIA        MD0040PA00X+010240Y+009260               S0      
317GND              VIA        MD0040PA00X+010460Y+009050               S0      
317GND              VIA        MD0040PA00X+010460Y+009500               S0      
317GND              VIA        MD0040PA00X+010680Y+009270               S0      
317GND              VIA        MD0040PA00X+042032Y+005607               S0      
317GND              VIA        MD0040PA00X+042320Y+005612               S0      
317GND              VIA        MD0040PA00X+042597Y+006205               S0      
317GND              VIA        MD0040PA00X+042607Y+005621               S0      
317GND              VIA        MD0040PA00X+042611Y+005905               S0      
317GND              VIA        MD0040PA00X+042613Y+005019               S0      
317GND              VIA        MD0040PA00X+042613Y+005335               S0      
317GND              VIA        MD0040PA00X+042906Y+005614               S0      
317GND              VIA        MD0040PA00X+043209Y+005615               S0      
317GND              VIA        MD0040PA00X+051970Y+018190               S0      
317GND              VIA        MD0040PA00X+052190Y+017950               S0      
317GND              VIA        MD0040PA00X+052190Y+018400               S0      
317GND              VIA        MD0040PA00X+052420Y+018160               S0      
317GND              VIA        MD0040PA00X+007700Y+014030               S0      
317GND              VIA        MD0040PA00X+007900Y+014250               S0      
317GND              VIA        MD0040PA00X+007920Y+013810               S0      
317GND              VIA        MD0040PA00X+008130Y+014040               S0      
317GND              VIA        MD0040PA00X+016330Y+017890               S0      
317GND              VIA        MD0040PA00X+016710Y+018120               S0      
317GND              VIA        MD0040PA00X+045666Y+007638               S0      
317GND              VIA        MD0040PA00X+046053Y+007656               S0      
317GND              VIA        MD0040PA00X+006420Y+009920               S0      
317GND              VIA        MD0040PA00X+006460Y+010450               S0      
317GND              VIA        MD0040PA00X+006720Y+006880               S0      
317GND              VIA        MD0040PA00X+006720Y+007240               S0      
317GND              VIA        MD0040PA00X+006740Y+007620               S0      
317GND              VIA        MD0040PA00X+007100Y+007350               S0      
317GND              VIA        MD0040PA00X+007110Y+006980               S0      
317GND              VIA        MD0040PA00X+007240Y+002230               S0      
317GND              VIA        MD0040PA00X+007350Y+007660               S0      
317GND              VIA        MD0040PA00X+007470Y+007310               S0      
317GND              VIA        MD0040PA00X+007480Y+006950               S0      
317GND              VIA        MD0040PA00X+007490Y+006580               S0      
317GND              VIA        MD0040PA00X+007550Y+005540               S0      
317GND              VIA        MD0040PA00X+007630Y+007970               S0      
317GND              VIA        MD0040PA00X+007800Y+010580               S0      
317GND              VIA        MD0040PA00X+007800Y+009990               S0      
317GND              VIA        MD0040PA00X+007820Y+007620               S0      
317GND              VIA        MD0040PA00X+007830Y+007260               S0      
317GND              VIA        MD0040PA00X+007840Y+006890               S0      
317GND              VIA        MD0040PA00X+007890Y+008240               S0      
317GND              VIA        MD0040PA00X+007910Y+005528               S0      
317GND              VIA        MD0040PA00X+008340Y+005530               S0      
317GND              VIA        MD0040PA00X+008730Y+005530               S0      
317GND              VIA        MD0040PA00X+009010Y+002310               S0      
317GND              VIA        MD0040PA00X+009591Y-005330               S0      
317P3V3                         D0040PA01X+014300Y+008600               S0      
317P3V3                         D0040PA01X+010859Y+018348               S0      
317P3V3                         D0040PA01X+014300Y+007870               S0      
327P3V3                         D0040PA01X+011060Y+019680               S0      
327P3V3                         D0040PA01X+014100Y+017710               S0      
317P3V3                         D0040PA00X+015390Y+022811               S0      
317P3V3                         D0040PA00X+015783Y+023598               S0      
317P3V3                         D0040PA00X+014996Y+021039               S0      
317P3V3                         D0040PA01X+015630Y+001860               S0      
317P3V3                         D0040PA01X+014300Y+008240               S0      
317P3V3                         D0040PA01X+010867Y+018731               S0      
327P3V3                         D0040PA01X+010920Y-001520               S0      
327P3V3                         D0040PA01X+010370Y+003440               S0      
317P3V3                         D0040PA01X+043460Y+001600               S0      
327P3V3                         D0040PA01X+013490Y+010300               S0      
317P3V3                         D0040PA00X+015390Y+014811               S0      
317P3V3                         D0040PA00X+015783Y+015598               S0      
317P3V3                         D0040PA00X+014996Y+013039               S0      
317P3V3                         D0040PA01X+010880Y+004570               S0      
317P3V3                         D0040PA01X+010867Y+019085               S0      
317P3V3             VIA        MD0040PA06X+015370Y+018280               S0      
317P3V3             VIA        MD0040PA01X+011030Y+003600               S0      
317P3V3             VIA        MD0040PA01X+012250Y-000660               S0      
317P3V3             VIA        MD0040PA00X+015330Y+002230               S0      
317P3V3             VIA        MD0040PA00X+043390Y+001100               S0      
317P3V3             VIA        MD0040PA00X+010200Y+004030               S0      
317P3V3             VIA        MD0040PA00X+010300Y+002830               S0      
317P3V3             VIA        MD0040PA00X+010580Y+004020               S0      
317P3V3             VIA        MD0040PA00X+010700Y+002830               S0      
317P3V3             VIA        MD0040PA00X+010780Y+000430               S0      
317P3V3             VIA        MD0040PA00X+010960Y+004000               S0      
317P3V3             VIA        MD0040PA00X+011080Y+002810               S0      
317P3V3             VIA        MD0040PA00X+011160Y+000410               S0      
317P3V3             VIA        MD0040PA00X+011550Y+000400               S0      
317P3V3             VIA        MD0040PA00X+011930Y+000380               S0      
317P3V3             VIA        MD0040PA00X+012300Y+000380               S0      
317P3V3             VIA        MD0040PA00X+012700Y+000390               S0      
317P3V3             VIA        MD0040PA00X+013080Y+000400               S0      
317P3V3             VIA        MD0040PA00X+013127Y+008508               S0      
317P3V3             VIA        MD0040PA00X+013147Y+009478               S0      
317P3V3             VIA        MD0040PA00X+013167Y+007858               S0      
317P3V3             VIA        MD0040PA00X+013490Y+016570               S0      
317P3V3             VIA        MD0040PA00X+013503Y+008509               S0      
317P3V3             VIA        MD0040PA00X+013510Y+016190               S0      
317P3V3             VIA        MD0040PA00X+013523Y+009479               S0      
317P3V3             VIA        MD0040PA00X+013543Y+007859               S0      
317P3V3             VIA        MD0040PA00X+013663Y+011812               S0      
317P3V3             VIA        MD0040PA00X+013872Y+008514               S0      
317P3V3             VIA        MD0040PA00X+013892Y+009484               S0      
317P3V3             VIA        MD0040PA00X+013912Y+007864               S0      
317P3V3             VIA        MD0040PA00X+014055Y+011791               S0      
317P3V3             VIA        MD0040PA00X+014250Y+020390               S0      
317P3V3             VIA        MD0040PA00X+014530Y+020110               S0      
317P3V3             VIA        MD0040PA00X+014616Y+012004               S0      
317P3V3             VIA        MD0040PA00X+014831Y+020375               S0      
317P3V3             VIA        MD0040PA00X+015170Y+016630               S0      
317P3V3             VIA        MD0040PA00X+015560Y+016630               S0      
317P3V3_STBY                    D0040PA01X+037708Y+001332               S0      
317P3V3_STBY                    D0040PA01X+037670Y-000120               S0      
317P3V3_STBY                    D0040PA01X+007870Y+016380               S0      
327P3V3_STBY                    D0040PA01X+009857Y+009572               S0      
317P3V3_STBY                    D0040PA01X+028900Y+019680               S0      
317P3V3_STBY                    D0040PA01X+018115Y+016664               S0      
317P3V3_STBY                    D0040PA01X+008750Y+021040               S0      
317P3V3_STBY                    D0040PA01X+038022Y+005962               S0      
317P3V3_STBY                    D0040PA01X+017130Y+018960               S0      
317P3V3_STBY                    D0040PA01X+036560Y+003540               S0      
317P3V3_STBY                    D0040PA01X+023003Y+019520               S0      
317P3V3_STBY                    D0040PA01X+011180Y+001790               S0      
317P3V3_STBY                    D0040PA01X+030700Y+018560               S0      
327P3V3_STBY                    D0040PA01X+010804Y+006595               S0      
317P3V3_STBY                    D0040PA01X+009808Y+013180               S0      
327P3V3_STBY                    D0040PA01X+036684Y+006805               S0      
317P3V3_STBY                    D0040PA01X+023420Y+016800               S0      
317P3V3_STBY                    D0040PA01X+009070Y+010070               S0      
317P3V3_STBY                    D0040PA01X+018518Y+016664               S0      
317P3V3_STBY                    D0040PA01X+009936Y+014406               S0      
317P3V3_STBY                    D0040PA01X+038380Y+000330               S0      
317P3V3_STBY                    D0040PA01X+024300Y+017650               S0      
317P3V3_STBY                    D0040PA01X+009570Y+016140               S0      
317P3V3_STBY                    D0040PA01X+033210Y+003940               S0      
317P3V3_STBY                    D0040PA01X+052611Y+016250               S0      
317P3V3_STBY                    D0040PA01X+030990Y+011640               S0      
317P3V3_STBY                    D0040PA01X+024320Y+018900               S0      
317P3V3_STBY                    D0040PA01X+024320Y+019320               S0      
317P3V3_STBY                    D0040PA01X+009570Y+017230               S0      
317P3V3_STBY                    D0040PA01X+019200Y+018150               S0      
317P3V3_STBY                    D0040PA01X+038020Y+004250               S0      
317P3V3_STBY                    D0040PA01X+040870Y+003340               S0      
317P3V3_STBY                    D0040PA01X+030700Y+017470               S0      
327P3V3_STBY                    D0040PA01X+012546Y+005925               S0      
317P3V3_STBY                    D0040PA01X+038680Y+005960               S0      
317P3V3_STBY                    D0040PA01X+007150Y+021040               S0      
317P3V3_STBY                    D0040PA01X+012122Y+009356               S0      
317P3V3_STBY                    D0040PA01X+005590Y+020700               S0      
317P3V3_STBY                    D0040PA01X+005960Y+020690               S0      
317P3V3_STBY                    D0040PA01X+005930Y+015430               S0      
317P3V3_STBY                    D0040PA01X+006530Y+014690               S0      
317P3V3_STBY                    D0040PA01X+052790Y+019630               S0      
327P3V3_STBY                    D0040PA01X+036364Y+003105               S0      
317P3V3_STBY                    D0040PA01X+006750Y+015420               S0      
317P3V3_STBY                    D0040PA01X+037710Y+002560               S0      
317P3V3_STBY                    D0040PA01X+009590Y+021040               S0      
317P3V3_STBY                    D0040PA00X+015783Y+021039               S0      
317P3V3_STBY                    D0040PA01X+021050Y+019580               S0      
317P3V3_STBY                    D0040PA01X+030211Y+019801               S0      
317P3V3_STBY                    D0040PA01X+016340Y+018940               S0      
317P3V3_STBY                    D0040PA01X+005630Y+016830               S0      
317P3V3_STBY                    D0040PA01X+029680Y+017180               S0      
317P3V3_STBY                    D0040PA01X+037690Y+000330               S0      
327P3V3_STBY                    D0040PA01X+006620Y+019584               S0      
327P3V3_STBY                    D0040PA01X+019810Y+017241               S0      
327P3V3_STBY                    D0040PA01X+019810Y+018859               S0      
327P3V3_STBY                    D0040PA01X+052487Y+018781               S0      
317P3V3_STBY                    D0040PA01X+038000Y+006950               S0      
317P3V3_STBY                    D0040PA01X+042800Y+010270               S0      
317P3V3_STBY                    D0040PA01X+033440Y+006960               S0      
317P3V3_STBY                    D0040PA01X+038680Y+004660               S0      
317P3V3_STBY                    D0040PA01X+013310Y+005620               S0      
317P3V3_STBY                    D0040PA01X+007550Y+021040               S0      
317P3V3_STBY                    D0040PA01X+043670Y+011260               S0      
327P3V3_STBY                    D0040PA01X+011480Y-006391               S0      
317P3V3_STBY                    D0040PA01X+016750Y+018960               S0      
317P3V3_STBY                    D0040PA01X+038020Y+004660               S0      
317P3V3_STBY                    D0040PA01X+008350Y+021040               S0      
317P3V3_STBY                    D0040PA01X+017060Y+010790               S0      
317P3V3_STBY                    D0040PA01X+038690Y+006950               S0      
317P3V3_STBY                    D0040PA01X+023430Y+017910               S0      
327P3V3_STBY                    D0040PA01X+040233Y+002859               S0      
317P3V3_STBY                    D0040PA01X+006780Y+016380               S0      
317P3V3_STBY                    D0040PA01X+028680Y+016840               S0      
317P3V3_STBY                    D0040PA01X+032700Y+001970               S0      
317P3V3_STBY                    D0040PA01X+029680Y+016760               S0      
317P3V3_STBY                    D0040PA01X+016475Y+019833               S0      
317P3V3_STBY                    D0040PA01X+009170Y+021040               S0      
317P3V3_STBY                    D0040PA01X+038370Y+002580               S0      
317P3V3_STBY                    D0040PA01X+019741Y+011700               S0      
317P3V3_STBY                    D0040PA01X+008330Y+015850               S0      
317P3V3_STBY                    D0040PA01X+023420Y+019850               S0      
327P3V3_STBY                    D0040PA01X+028214Y+019650               S0      
317P3V3_STBY                    D0040PA01X+010250Y+006580               S0      
317P3V3_STBY                    D0040PA01X+051753Y+016240               S0      
327P3V3_STBY                    D0040PA01X+007307Y+014324               S0      
317P3V3_STBY                    D0040PA01X+032780Y+003930               S0      
317P3V3_STBY                    D0040PA01X+024480Y+011760               S0      
317P3V3_STBY                    D0040PA01X+013700Y+005630               S0      
317P3V3_STBY                    D0040PA01X+010760Y+001780               S0      
317P3V3_STBY                    D0040PA00X+015783Y+013039               S0      
317P3V3_STBY                    D0040PA01X+007950Y+021040               S0      
317P3V3_STBY                    D0040PA01X+033280Y+005220               S0      
317P3V3_STBY                    D0040PA01X+038370Y+001320               S0      
317P3V3_STBY                    D0040PA01X+017140Y+010380               S0      
317P3V3_STBY                    D0040PA01X+029680Y+018780               S0      
317P3V3_STBY                    D0040PA01X+036680Y+007250               S0      
317P3V3_STBY                    D0040PA01X+024300Y+018060               S0      
317P3V3_STBY                    D0040PA01X+030110Y+017480               S0      
317P3V3_STBY                    D0040PA01X+033070Y+006470               S0      
317P3V3_STBY                    D0040PA01X+011261Y+010978               S0      
317P3V3_STBY        VIA        MD0040PA06X+012500Y+003630               S0      
317P3V3_STBY        VIA        MD0040PA06X+020370Y+019400               S0      
317P3V3_STBY        VIA        MD0040PA06X+029330Y+018820               S0      
317P3V3_STBY        VIA        MD0040PA06X+042780Y+007490               S0      
317P3V3_STBY        VIA        MD0040PA06X+051790Y+015740               S0      
317P3V3_STBY        VIA        MD0040PA06X+005550Y+016840               S0      
317P3V3_STBY        VIA        MD0040PA06X+009320Y+006910               S0      
317P3V3_STBY        VIA        MD0040PA00X+010050Y+020930               S0      
317P3V3_STBY        VIA        MD0040PA00X+010150Y+013990               S0      
317P3V3_STBY        VIA        MD0040PA00X+010220Y+013180               S0      
317P3V3_STBY        VIA        MD0040PA00X+011180Y+011370               S0      
317P3V3_STBY        VIA        MD0040PA00X+012500Y+009340               S0      
317P3V3_STBY        VIA        MD0040PA00X+013740Y+006190               S0      
317P3V3_STBY        VIA        MD0040PA00X+016420Y+020510               S0      
317P3V3_STBY        VIA        MD0040PA00X+017230Y+019280               S0      
317P3V3_STBY        VIA        MD0040PA00X+018890Y+017330               S0      
317P3V3_STBY        VIA        MD0040PA00X+019160Y+018560               S0      
317P3V3_STBY        VIA        MD0040PA00X+019830Y+011170               S0      
317P3V3_STBY        VIA        MD0040PA00X+020940Y+020010               S0      
317P3V3_STBY        VIA        MD0040PA00X+022510Y+016810               S0      
317P3V3_STBY        VIA        MD0040PA00X+022560Y+018590               S0      
317P3V3_STBY        VIA        MD0040PA00X+023050Y+019140               S0      
317P3V3_STBY        VIA        MD0040PA00X+024680Y+011250               S0      
317P3V3_STBY        VIA        MD0040PA00X+028960Y+016210               S0      
317P3V3_STBY        VIA        MD0040PA00X+029460Y+020130               S0      
317P3V3_STBY        VIA        MD0040PA00X+030150Y+018630               S0      
317P3V3_STBY        VIA        MD0040PA00X+030860Y+017110               S0      
317P3V3_STBY        VIA        MD0040PA00X+031340Y+011910               S0      
317P3V3_STBY        VIA        MD0040PA00X+032460Y+003690               S0      
317P3V3_STBY        VIA        MD0040PA00X+032940Y+005030               S0      
317P3V3_STBY        VIA        MD0040PA00X+033910Y+007330               S0      
317P3V3_STBY        VIA        MD0040PA00X+036240Y+003450               S0      
317P3V3_STBY        VIA        MD0040PA00X+038020Y+002580               S0      
317P3V3_STBY        VIA        MD0040PA00X+038020Y+000330               S0      
317P3V3_STBY        VIA        MD0040PA00X+038050Y+001320               S0      
317P3V3_STBY        VIA        MD0040PA00X+038340Y+004660               S0      
317P3V3_STBY        VIA        MD0040PA00X+038350Y+006920               S0      
317P3V3_STBY        VIA        MD0040PA00X+038360Y+005962               S0      
317P3V3_STBY        VIA        MD0040PA00X+040450Y+003630               S0      
317P3V3_STBY        VIA        MD0040PA00X+043900Y+008770               S0      
317P3V3_STBY        VIA        MD0040PA00X+052050Y+015450               S0      
317P3V3_STBY        VIA        MD0040PA00X+052500Y+015800               S0      
317P3V3_STBY        VIA        MD0040PA00X+052850Y+020000               S0      
317P3V3_STBY        VIA        MD0040PA00X+005640Y+016425               S0      
317P3V3_STBY        VIA        MD0040PA00X+005650Y+020290               S0      
317P3V3_STBY        VIA        MD0040PA00X+005940Y+015100               S0      
317P3V3_STBY        VIA        MD0040PA00X+006610Y+015100               S0      
317P3V3_STBY        VIA        MD0040PA00X+006775Y+016070               S0      
317P3V3_STBY        VIA        MD0040PA00X+008000Y+015890               S0      
317P3V3_STBY        VIA        MD0040PA00X+008040Y+016720               S0      
317P3V3_STBY        VIA        MD0040PA00X+008725Y+010065               S0      
317P3V3_STBY        VIA        MD0040PA00X+009240Y+016310               S0      
317P3V3_STBY        VIA        MD0040PA00X+009830Y+006750               S0      
317P3V3_STBY        VIA        MD0040PA00X+009890Y+017235               S0      
317P3V3_STBY        VIA        MD0040PA00X+015228Y+003688               S0      
317P3V3_STBY        VIA        MD0040PA00X+015270Y+003330               S0      
317P3V3_STBY        VIA        MD0040PA00X+015300Y+004070               S0      
317P3V3_STBY        VIA        MD0040PA00X+015800Y+012090               S0      
317P3V3_STBY        VIA        MD0040PA00X+015800Y+012480               S0      
317P3V3_STBY        VIA        MD0040PA00X+015810Y+011630               S0      
317P3V3_STBY        VIA        MD0040PA00X+016210Y+019380               S0      
317P3V3_STBY        VIA        MD0040PA00X+016570Y+019500               S0      
317P3V3_STBY        VIA        MD0040PA00X+016980Y+009110               S0      
317P3V3_STBY        VIA        MD0040PA00X+017230Y+009430               S0      
317P3V3_STBY        VIA        MD0040PA00X+017490Y+009090               S0      
317P3V3_STBY        VIA        MD0040PA00X+036370Y+007820               S0      
317P3V3_STBY        VIA        MD0040PA00X+042420Y+010380               S0      
317P3V3_STBY        VIA        MD0040PA00X+042850Y+010770               S0      
317P3V3_STBY        VIA        MD0040PA00X+043210Y+010380               S0      
317P3V3_STBY        VIA        MD0040PA00X+008980Y+007670               S0      
317P3V3_STBY        VIA        MD0040PA00X+009300Y+007330               S0      
317P3V3_STBY        VIA        MD0040PA00X+009380Y+007700               S0      
317P3V3_STBY        VIA        MD0040PA00X+009600Y+008010               S0      
317P3V3_STBY        VIA        MD0040PA00X+009780Y+007680               S0      
317P12V_SLOT3                   D0040PA01X+008955Y+022353               S0      
317P12V_SLOT3                   D0040PA01X+004913Y+015471               S0      
317P12V_SLOT3                   D0040PA01X+009440Y+022341               S0      
317P12V_SLOT3                   D0040PA01X+009916Y+022342               S0      
317P12V_SLOT3                   D0040PA00X+012634Y+023598               S0      
317P12V_SLOT3                   D0040PA00X+013028Y+022811               S0      
317P12V_SLOT3                   D0040PA00X+012240Y+021827               S0      
317P12V_SLOT3                   D0040PA00X+012634Y+021039               S0      
317P12V_SLOT3                   D0040PA00X+013028Y+021827               S0      
327P12V_SLOT3                   D0040PA01X+004450Y+019590               S0      
317P12V_SLOT3                   D0040PA01X+008463Y+022354               S0      
317P12V_SLOT3                   D0040PA01X+004601Y+016209               S0      
317P12V_SLOT3       VIA        MD0040PA01X+005090Y+016680               S0      
317P12V_SLOT3       VIA        MD0040PA01X+007410Y+022190               S0      
317P12V_SLOT3       VIA        MD0040PA00X+003920Y+021210               S0      
317P12V_SLOT3       VIA        MD0040PA00X+003930Y+021740               S0      
317P12V_SLOT3       VIA        MD0040PA00X+004420Y+021220               S0      
317P12V_SLOT3       VIA        MD0040PA00X+004440Y+021740               S0      
317P12V                         D0040PA01X+015710Y+007880               S0      
327P12V                         D0040PA01X+009857Y+009178               S0      
317P12V                         D0040PA01X+051268Y+020550               S0      
317P12V                         D0040PA01X+009160Y+009120               S0      
327P12V                         D0040PA01X+052094Y+018781               S0      
327P12V                         D0040PA01X+007701Y-006391               S0      
327P12V                         D0040PA06X+007701Y-006391               S0      
327P12V                         D0040PA01X+008016Y-006391               S0      
327P12V                         D0040PA06X+008016Y-006391               S0      
327P12V                         D0040PA01X+008331Y-006391               S0      
327P12V                         D0040PA06X+008331Y-006391               S0      
327P12V                         D0040PA01X+008646Y-006391               S0      
327P12V                         D0040PA06X+008646Y-006391               S0      
327P12V                         D0040PA01X+008961Y-006391               S0      
327P12V                         D0040PA06X+008961Y-006391               S0      
327P12V                         D0040PA01X+009276Y-006391               S0      
327P12V                         D0040PA06X+009276Y-006391               S0      
317P12V                         D0040PA01X+052060Y+019660               S0      
317P12V                         D0040PA01X+015700Y+007420               S0      
327P12V                         D0040PA01X+002800Y+007550               S0      
317P12V                         D0040PA01X+003971Y+009791               S0      
317P12V                         D0040PA01X+004629Y+015180               S0      
317P12V                         D0040PA01X+006560Y+013940               S0      
327P12V                         D0040PA01X+007307Y+013930               S0      
317P12V                         D0040PA01X+003823Y+015431               S0      
317P12V                         D0040PA01X+004553Y+009477               S0      
327P12V                         D0040PA01X+050999Y+021206               S0      
317P12V                         D0040PA06X+004210Y+009440               S0      
317P12V             VIA        MD0040PA06X+003685Y+015799               S0      
317P12V             VIA        MD0040PA06X+008410Y-001950               S0      
317P12V             VIA        MD0040PA01X+050960Y+022010               S0      
317P12V             VIA        MD0040PA00X+014790Y+007380               S0      
317P12V             VIA        MD0040PA00X+052097Y+019257               S0      
317P12V             VIA        MD0040PA00X+006880Y+013900               S0      
317P12V             VIA        MD0040PA00X+008790Y+009450               S0      
317P12V             VIA        MD0040PA00X+002160Y+007400               S0      
317P12V             VIA        MD0040PA00X+002180Y+007860               S0      
317P12V             VIA        MD0040PA00X+002230Y+008500               S0      
317P12V             VIA        MD0040PA00X+002440Y+008190               S0      
317P12V             VIA        MD0040PA00X+002570Y+008920               S0      
317P12V             VIA        MD0040PA00X+002721Y+008529               S0      
317P12V             VIA        MD0040PA00X+002820Y+016040               S0      
317P12V             VIA        MD0040PA00X+002920Y+016400               S0      
317P12V             VIA        MD0040PA00X+002940Y+009230               S0      
317P12V             VIA        MD0040PA00X+003060Y+008810               S0      
317P12V             VIA        MD0040PA00X+003100Y+015690               S0      
317P12V             VIA        MD0040PA00X+003240Y+016060               S0      
317P12V             VIA        MD0040PA00X+003280Y+009500               S0      
317P12V             VIA        MD0040PA00X+003310Y+016480               S0      
317P12V             VIA        MD0040PA00X+003320Y+009870               S0      
317P12V             VIA        MD0040PA00X+003370Y+009140               S0      
317P12V             VIA        MD0040PA00X+003600Y+016180               S0      
317P12V             VIA        MD0040PA00X+044980Y-001350               S0      
317P12V             VIA        MD0040PA00X+044990Y-000570               S0      
317P12V             VIA        MD0040PA00X+044990Y-000970               S0      
317P12V             VIA        MD0040PA00X+045000Y-000190               S0      
317P12V             VIA        MD0040PA00X+045340Y-001350               S0      
317P12V             VIA        MD0040PA00X+045350Y-000570               S0      
317P12V             VIA        MD0040PA00X+045350Y-000980               S0      
317P12V             VIA        MD0040PA00X+045360Y-000200               S0      
317P12V             VIA        MD0040PA00X+049540Y+021530               S0      
317P12V             VIA        MD0040PA00X+049550Y+021050               S0      
317P12V             VIA        MD0040PA00X+049550Y+021960               S0      
317P12V             VIA        MD0040PA00X+050010Y+021520               S0      
317P12V             VIA        MD0040PA00X+050020Y+021040               S0      
317P12V             VIA        MD0040PA00X+050020Y+021950               S0      
317P12V             VIA        MD0040PA00X+050450Y+021060               S0      
317P12V             VIA        MD0040PA00X+050470Y+021530               S0      
317P12V             VIA        MD0040PA00X+050480Y+021960               S0      
317P12V             VIA        MD0040PA00X+007904Y-003070               S0      
317P12V             VIA        MD0040PA00X+007910Y-003575               S0      
317P12V             VIA        MD0040PA00X+007944Y-004128               S0      
317P12V             VIA        MD0040PA00X+007944Y-004682               S0      
317P12V             VIA        MD0040PA00X+008462Y-002766               S0      
317P12V             VIA        MD0040PA00X+008467Y-004497               S0      
317P12V             VIA        MD0040PA00X+008523Y-003403               S0      
317P12V             VIA        MD0040PA00X+008544Y-003993               S0      
317P12V             VIA        MD0040PA00X+008947Y-004798               S0      
317P12V             VIA        MD0040PA00X+009033Y-003019               S0      
317P12V             VIA        MD0040PA00X+009040Y-003650               S0      
317P12V             VIA        MD0040PA00X+009055Y-004142               S0      
317RESET_IN                     D0040PA01X+015120Y+006270               S0      
317RESET_IN                     D0040PA01X+015690Y+006640               S0      
317RESET_IN                     D0040PA01X+015700Y+007080               S0      
317RESET_IN                     D0040PA01X+015710Y+006230               S0      
317RESET_IN         VIA        MD0040PA01X+015250Y+006780               S0      
327NNAME00000                   D0040PA01X+010172Y+008666               S0      
317NNAME00000                   D0040PA01X+005081Y+008980               S0      
317NNAME00000                   D0040PA01X+004793Y+009237               S0      
317NNAME00000       VIA        MD0040PA01X+008910Y+008100               S0      
327NNAME00001                   D0040PA01X+009857Y+008981               S0      
317NNAME00001                   D0040PA01X+005336Y+009234               S0      
317NNAME00001                   D0040PA01X+005081Y+009525               S0      
317NNAME00001       VIA        MD0040PA01X+009240Y+008530               S0      
317NNAME00002                   D0040PA01X+005147Y+014676               S0      
317NNAME00002                   D0040PA01X+004869Y+014939               S0      
327NNAME00002                   D0040PA01X+007623Y+013418               S0      
317NNAME00002       VIA        MD0040PA01X+005460Y+014060               S0      
317NNAME00003                   D0040PA01X+005154Y+015231               S0      
317NNAME00003                   D0040PA01X+005401Y+014931               S0      
327NNAME00003                   D0040PA01X+007307Y+013733               S0      
317NNAME00003       VIA        MD0040PA01X+005740Y+014600               S0      
317NNAME00004                   D0040PA01X+051268Y+020210               S0      
327NNAME00004                   D0040PA01X+051581Y+018466               S0      
317NNAME00004                   D0040PA01X+051308Y+019835               S0      
317NNAME00004       VIA        MD0040PA01X+050930Y+019840               S0      
327NNAME00005                   D0040PA01X+051897Y+018781               S0      
317NNAME00005                   D0040PA01X+051668Y+019835               S0      
317NNAME00005                   D0040PA01X+051681Y+020210               S0      
317NNAME00005       VIA        MD0040PA01X+051710Y+019460               S0      
327P12V_ATX                     D0040PA01X+054822Y+022420               S0      
327P12V_ATX                     D0040PA01X+052443Y+022420               S0      
327P12V_ATX                     D0040PA01X+054029Y+022420               S0      
317P12V_ATX                     D0040PA00X+053937Y+020679               S0      
317P12V_ATX                     D0040PA00X+053937Y+019026               S0      
317P12V_ATX                     D0040PA01X+051681Y+020550               S0      
327P12V_ATX                     D0040PA01X+053236Y+022420               S0      
327P12V_ATX                     D0040PA01X+052099Y+021206               S0      
317P12V_ATX         VIA        MD0040PA06X+051580Y+021950               S0      
317P12V_ATX         VIA        MD0040PA00X+051990Y+021950               S0      
317P12V_ATX         VIA        MD0040PA00X+052700Y+021950               S0      
317P12V_ATX         VIA        MD0040PA00X+053220Y+021930               S0      
317P12V_ATX         VIA        MD0040PA00X+054050Y+021950               S0      
317P3V3_USB_HUB                 D0040PA01X+044739Y+007404               S0      
317P3V3_USB_HUB                 D0040PA01X+045040Y+004050               S0      
317P3V3_USB_HUB                 D0040PA01X+040496Y+005127               S0      
327P3V3_USB_HUB                 D0040PA01X+042622Y+006726               S0      
327P3V3_USB_HUB                 D0040PA01X+041472Y+006393               S0      
327P3V3_USB_HUB                 D0040PA01X+041502Y+005409               S0      
327P3V3_USB_HUB                 D0040PA01X+042622Y+004486               S0      
327P3V3_USB_HUB                 D0040PA01X+043742Y+005015               S0      
327P3V3_USB_HUB                 D0040PA01X+043772Y+006393               S0      
317P3V3_USB_HUB                 D0040PA01X+042670Y+008410               S0      
317P3V3_USB_HUB                 D0040PA01X+041380Y+002270               S0      
317P3V3_USB_HUB                 D0040PA01X+045093Y+002949               S0      
317P3V3_USB_HUB                 D0040PA01X+045040Y+004430               S0      
317P3V3_USB_HUB                 D0040PA01X+044579Y+007838               S0      
317P3V3_USB_HUB                 D0040PA01X+040020Y+000450               S0      
317P3V3_USB_HUB                 D0040PA01X+042800Y+009710               S0      
317P3V3_USB_HUB                 D0040PA01X+040433Y+000442               S0      
317P3V3_USB_HUB                 D0040PA01X+041428Y+008408               S0      
317P3V3_USB_HUB                 D0040PA01X+043163Y+008430               S0      
317P3V3_USB_HUB                 D0040PA01X+042803Y+008871               S0      
317P3V3_USB_HUB                 D0040PA01X+041844Y+008405               S0      
327P3V3_USB_HUB                 D0040PA01X+040233Y+001241               S0      
317P3V3_USB_HUB                 D0040PA01X+042264Y+008408               S0      
317P3V3_USB_HUB                 D0040PA01X+042692Y+003822               S0      
317P3V3_USB_HUB                 D0040PA01X+043460Y+002160               S0      
317P3V3_USB_HUB                 D0040PA01X+041380Y+001180               S0      
317P3V3_USB_HUB                 D0040PA01X+043529Y+002961               S0      
317P3V3_USB_HUB                 D0040PA01X+040796Y+006561               S0      
317P3V3_USB_HUB     VIA        MD0040PA01X+042256Y+009463               S0      
317P3V3_USB_HUB     VIA        MD0040PA00X+040450Y+004777               S0      
317P3V3_USB_HUB     VIA        MD0040PA00X+040940Y+006980               S0      
317P3V3_USB_HUB     VIA        MD0040PA00X+041200Y+002990               S0      
317P3V3_USB_HUB     VIA        MD0040PA00X+042350Y+003780               S0      
317P3V3_USB_HUB     VIA        MD0040PA00X+042860Y+001690               S0      
317P3V3_USB_HUB     VIA        MD0040PA00X+043529Y+002565               S0      
317P3V3_USB_HUB     VIA        MD0040PA00X+044169Y+007491               S0      
317P3V3_USB_HUB     VIA        MD0040PA00X+044940Y+002643               S0      
317P3V3_USB_HUB     VIA        MD0040PA00X+045400Y+004060               S0      
317P3V3_USB_HUB     VIA        MD0040PA00X+041844Y+008773               S0      
317P3V3_USB_HUB     VIA        MD0040PA00X+042141Y+009090               S0      
317P3V3_USB_HUB     VIA        MD0040PA00X+042369Y+008788               S0      
327PLLFILT                      D0040PA01X+043742Y+006000               S0      
317PLLFILT                      D0040PA01X+044883Y+006018               S0      
317PLLFILT          VIA        MD0040PA01X+044519Y+006278               S0      
327NNAME00006                   D0040PA01X+043742Y+005803               S0      
317NNAME00006                   D0040PA01X+046144Y+006011               S0      
327NNAME00006                   D0040PA01X+045916Y+006611               S0      
317NNAME00006       VIA        MD0040PA01X+044506Y+005798               S0      
317NNAME00007                   D0040PA01X+046539Y+006010               S0      
327NNAME00007                   D0040PA01X+043742Y+005606               S0      
327NNAME00007                   D0040PA01X+046838Y+007207               S0      
317NNAME00007       VIA        MD0040PA01X+046392Y+005619               S0      
327VBUS_DET                     D0040PA01X+043409Y+004456               S0      
317VBUS_DET                     D0040PA01X+044753Y+002949               S0      
317VBUS_DET                     D0040PA01X+044752Y+003331               S0      
317VBUS_DET         VIA        MD0040PA01X+044480Y+003710               S0      
327CRFILT                       D0040PA01X+041502Y+005606               S0      
317CRFILT                       D0040PA01X+040490Y+005487               S0      
317CRFILT           VIA        MD0040PA01X+040880Y+005550               S0      
327NNAME00008                   D0040PA01X+044785Y-006431               S0      
317NNAME00008                   D0040PA00X+032319Y+021039               S0      
327NNAME00009                   D0040PA01X+045100Y-006431               S0      
317NNAME00009                   D0040PA00X+032713Y+021827               S0      
327NNAME00010                   D0040PA06X+045100Y-006431               S0      
317NNAME00010                   D0040PA00X+033106Y+023598               S0      
327NNAME00011                   D0040PA06X+045415Y-006431               S0      
317NNAME00011                   D0040PA00X+033500Y+022811               S0      
327NNAME00012                   D0040PA01X+045730Y-006431               S0      
317NNAME00012                   D0040PA00X+033894Y+021039               S0      
327NNAME00013                   D0040PA01X+046045Y-006431               S0      
317NNAME00013                   D0040PA00X+034287Y+021827               S0      
327NNAME00014                   D0040PA06X+046045Y-006431               S0      
317NNAME00014                   D0040PA00X+034681Y+023598               S0      
327NNAME00015                   D0040PA06X+046360Y-006431               S0      
317NNAME00015                   D0040PA00X+035075Y+022811               S0      
327NNAME00016                   D0040PA01X+046675Y-006431               S0      
317NNAME00016                   D0040PA00X+035468Y+021039               S0      
327NNAME00017                   D0040PA01X+046990Y-006431               S0      
317NNAME00017                   D0040PA00X+035862Y+021827               S0      
327NNAME00018                   D0040PA06X+046990Y-006431               S0      
317NNAME00018                   D0040PA00X+036256Y+023598               S0      
327NNAME00019                   D0040PA06X+047305Y-006431               S0      
317NNAME00019                   D0040PA00X+036650Y+022811               S0      
327NNAME00020                   D0040PA01X+047620Y-006431               S0      
317NNAME00020                   D0040PA00X+037043Y+021039               S0      
327NNAME00021                   D0040PA01X+047935Y-006431               S0      
317NNAME00021                   D0040PA00X+037437Y+021827               S0      
327NNAME00022                   D0040PA06X+047935Y-006431               S0      
317NNAME00022                   D0040PA00X+037831Y+023598               S0      
327NNAME00023                   D0040PA06X+048250Y-006431               S0      
317NNAME00023                   D0040PA00X+038224Y+022811               S0      
327NNAME00024                   D0040PA01X+048565Y-006431               S0      
317NNAME00024                   D0040PA00X+038618Y+021039               S0      
327NNAME00025                   D0040PA01X+048880Y-006431               S0      
317NNAME00025                   D0040PA00X+039012Y+021827               S0      
327NNAME00026                   D0040PA06X+048880Y-006431               S0      
317NNAME00026                   D0040PA00X+039405Y+023598               S0      
327NNAME00027                   D0040PA06X+049195Y-006431               S0      
317NNAME00027                   D0040PA00X+039799Y+022811               S0      
327NNAME00028                   D0040PA01X+049510Y-006431               S0      
317NNAME00028                   D0040PA00X+040193Y+021039               S0      
327NNAME00029                   D0040PA01X+049825Y-006431               S0      
317NNAME00029                   D0040PA00X+040587Y+021827               S0      
327NNAME00030                   D0040PA06X+049825Y-006431               S0      
317NNAME00030                   D0040PA00X+040980Y+023598               S0      
327NNAME00031                   D0040PA06X+050140Y-006431               S0      
317NNAME00031                   D0040PA00X+041374Y+022811               S0      
327NNAME00032                   D0040PA01X+050455Y-006431               S0      
317NNAME00032                   D0040PA00X+041768Y+021039               S0      
327NNAME00033                   D0040PA01X+050770Y-006431               S0      
317NNAME00033                   D0040PA00X+042161Y+021827               S0      
327NNAME00034                   D0040PA06X+050770Y-006431               S0      
317NNAME00034                   D0040PA00X+042555Y+023598               S0      
327NNAME00035                   D0040PA06X+051085Y-006431               S0      
317NNAME00035                   D0040PA00X+042949Y+022811               S0      
327NNAME00036                   D0040PA01X+051400Y-006431               S0      
317NNAME00036                   D0040PA00X+043342Y+021039               S0      
327NNAME00037                   D0040PA01X+051715Y-006431               S0      
317NNAME00037                   D0040PA00X+043736Y+021827               S0      
327NNAME00038                   D0040PA06X+051715Y-006431               S0      
317NNAME00038                   D0040PA00X+044130Y+023598               S0      
327NNAME00039                   D0040PA06X+052030Y-006431               S0      
317NNAME00039                   D0040PA00X+044524Y+022811               S0      
317USB2_P02_DN                  D0040PA01X+045381Y+004847               S0      
327USB2_P02_DN                  D0040PA01X+053289Y-006431               S0      
317USB2_P02_DN      VIA        MD0040PA00X+046151Y+004876               S0      
317USB2_P02_DN      VIA        MD0040PA00X+052499Y-003800               S0      
327USB2_P02_DP                  D0040PA01X+053604Y-006431               S0      
317USB2_P02_DP                  D0040PA01X+045379Y+005254               S0      
317USB2_P02_DP      VIA        MD0040PA00X+046151Y+005227               S0      
317USB2_P02_DP      VIA        MD0040PA00X+053099Y-003800               S0      
317NNAME00040                   D0040PA01X+006340Y+021040               S0      
327NNAME00040                   D0040PA01X+009906Y-006391               S0      
317NNAME00040       VIA        MD0040PA06X+009136Y+001254               S0      
317NNAME00040       VIA        MD0040PA00X+006400Y+021350               S0      
317NNAME00040       VIA        MD0040PA00X+009404Y+000984               S0      
317NNAME00041                   D0040PA01X+007150Y+020700               S0      
327NNAME00041                   D0040PA01X+007388Y+019584               S0      
327NNAME00041                   D0040PA06X+009906Y-006391               S0      
317NNAME00041       VIA        MD0040PA06X+009030Y+005960               S0      
317NNAME00041       VIA        MD0040PA00X+007220Y+020240               S0      
317NNAME00041       VIA        MD0040PA00X+008800Y+006520               S0      
327NNAME00042                   D0040PA01X+010221Y-006391               S0      
317NNAME00042                   D0040PA01X+006740Y+021040               S0      
317NNAME00042       VIA        MD0040PA06X+009820Y+000620               S0      
317NNAME00042       VIA        MD0040PA00X+006750Y+021350               S0      
317NNAME00042       VIA        MD0040PA00X+009820Y+001000               S0      
317FM_SLT_CFG1                  D0040PA01X+011180Y+001450               S0      
327FM_SLT_CFG1                  D0040PA01X+036684Y+004501               S0      
317FM_SLT_CFG1                  D0040PA01X+011600Y+001450               S0      
327FM_SLT_CFG1                  D0040PA01X+036364Y+000801               S0      
327FM_SLT_CFG1                  D0040PA06X+010221Y-006391               S0      
317FM_SLT_CFG1      VIA        MD0040PA06X+010270Y+000200               S0      
317FM_SLT_CFG1      VIA        MD0040PA00X+011102Y+001138               S0      
317FM_SLT_CFG1      VIA        MD0040PA00X+036210Y+003810               S0      
317FM_SLT_CFG1      VIA        MD0040PA00X+037240Y+004110               S0      
317FM_SLT_CFG0                  D0040PA01X+010330Y+001440               S0      
327FM_SLT_CFG0                  D0040PA01X+036684Y+004245               S0      
327FM_SLT_CFG0                  D0040PA01X+036364Y+000545               S0      
327FM_SLT_CFG0                  D0040PA01X+010536Y-006391               S0      
317FM_SLT_CFG0                  D0040PA01X+010760Y+001440               S0      
317FM_SLT_CFG0      VIA        MD0040PA06X+010690Y+001570               S0      
317FM_SLT_CFG0      VIA        MD0040PA00X+010740Y+001130               S0      
317FM_SLT_CFG0      VIA        MD0040PA00X+035870Y+003810               S0      
317NNAME00043                   D0040PA00X+024445Y+021039               S0      
327NNAME00043                   D0040PA06X+010536Y-006391               S0      
317NNAME00043                   D0040PA00X+024445Y+013039               S0      
317NNAME00043       VIA        MD0040PA06X+012652Y-000448               S0      
317NNAME00043       VIA        MD0040PA00X+015430Y+004960               S0      
317NNAME00043       VIA        MD0040PA00X+023370Y+005440               S0      
327P3V3_MB                      D0040PA01X+010850Y-006391               S0      
327P3V3_MB                      D0040PA06X+010850Y-006391               S0      
327P3V3_MB                      D0040PA01X+011165Y-006391               S0      
327P3V3_MB                      D0040PA06X+011165Y-006391               S0      
327P3V3_MB                      D0040PA01X+010920Y-002620               S0      
317P3V3_MB          VIA        MD0040PA06X+010930Y-002800               S0      
317P3V3_MB          VIA        MD0040PA00X+010680Y-005300               S0      
317P3V3_MB          VIA        MD0040PA00X+010700Y-004900               S0      
317P3V3_MB          VIA        MD0040PA00X+010710Y-003690               S0      
317P3V3_MB          VIA        MD0040PA00X+010750Y-003320               S0      
317P3V3_MB          VIA        MD0040PA00X+011110Y-005310               S0      
317P3V3_MB          VIA        MD0040PA00X+011130Y-004910               S0      
317P3V3_MB          VIA        MD0040PA00X+011140Y-003700               S0      
317P3V3_MB          VIA        MD0040PA00X+011180Y-003330               S0      
327NNAME00044                   D0040PA01X+011795Y-006391               S0      
327NNAME00044                   D0040PA01X+015571Y-000004               S0      
317NNAME00044       VIA        MD0040PA01X+014200Y-003020               S0      
317NNAME00045                   D0040PA00X+016177Y+021827               S0      
327NNAME00045                   D0040PA06X+011795Y-006391               S0      
317NNAME00045                   D0040PA00X+016177Y+013827               S0      
317NNAME00045       VIA        MD0040PA06X+016920Y+018800               S0      
317NNAME00045       VIA        MD0040PA00X+016169Y+005511               S0      
327PERST_N                      D0040PA01X+012546Y+006575               S0      
327PERST_N                      D0040PA01X+012110Y-006391               S0      
317PERST_N          VIA        MD0040PA06X+017360Y+003920               S0      
317PERST_N          VIA        MD0040PA00X+012940Y+006220               S0      
317PERST_N          VIA        MD0040PA00X+016980Y+003920               S0      
317NNAME00046                   D0040PA01X+030540Y+019370               S0      
327NNAME00046                   D0040PA01X+020322Y+017241               S0      
327NNAME00046                   D0040PA06X+012110Y-006391               S0      
317NNAME00046       VIA        MD0040PA01X+032170Y+019010               S0      
317NNAME00046       VIA        MD0040PA00X+014788Y+001333               S0      
317NNAME00046       VIA        MD0040PA00X+019590Y+016210               S0      
317NNAME00046       VIA        MD0040PA00X+032324Y+018332               S0      
317NNAME00047                   D0040PA01X+030540Y+018970               S0      
327NNAME00047                   D0040PA01X+020066Y+017241               S0      
327NNAME00047                   D0040PA06X+012425Y-006391               S0      
317NNAME00047       VIA        MD0040PA01X+030950Y+019030               S0      
317NNAME00047       VIA        MD0040PA00X+014830Y+001670               S0      
317NNAME00047       VIA        MD0040PA00X+019220Y+016670               S0      
317NNAME00047       VIA        MD0040PA00X+032160Y+018630               S0      
327NNAME00048                   D0040PA01X+012740Y-006391               S0      
317NNAME00048                   D0040PA00X+017752Y+014811               S0      
327NNAME00049                   D0040PA01X+013055Y-006391               S0      
317NNAME00049                   D0040PA00X+018146Y+015598               S0      
317NNAME00050                   D0040PA00X+017752Y+022811               S0      
327NNAME00050                   D0040PA06X+013055Y-006391               S0      
317NNAME00051                   D0040PA00X+018146Y+023598               S0      
327NNAME00051                   D0040PA06X+013370Y-006391               S0      
327NNAME00052                   D0040PA01X+015575Y-006391               S0      
317NNAME00052                   D0040PA00X+018146Y+013039               S0      
327NNAME00053                   D0040PA01X+015890Y-006391               S0      
317NNAME00053                   D0040PA00X+018539Y+013827               S0      
327NNAME00054                   D0040PA06X+015890Y-006391               S0      
317NNAME00054                   D0040PA00X+018933Y+015598               S0      
327NNAME00055                   D0040PA06X+016205Y-006391               S0      
317NNAME00055                   D0040PA00X+019327Y+014811               S0      
327NNAME00056                   D0040PA01X+016520Y-006391               S0      
317NNAME00056                   D0040PA00X+020114Y+013827               S0      
327NNAME00057                   D0040PA01X+016835Y-006391               S0      
317NNAME00057                   D0040PA00X+020508Y+013039               S0      
327NNAME00058                   D0040PA06X+016835Y-006391               S0      
317NNAME00058                   D0040PA00X+020902Y+014811               S0      
327NNAME00059                   D0040PA06X+017150Y-006391               S0      
317NNAME00059                   D0040PA00X+021295Y+015598               S0      
327NNAME00060                   D0040PA01X+019354Y-006391               S0      
317NNAME00060                   D0040PA00X+021689Y+013827               S0      
327NNAME00061                   D0040PA01X+019669Y-006391               S0      
317NNAME00061                   D0040PA00X+022083Y+013039               S0      
327NNAME00062                   D0040PA06X+019669Y-006391               S0      
317NNAME00062                   D0040PA00X+022476Y+014811               S0      
327NNAME00063                   D0040PA06X+019984Y-006391               S0      
317NNAME00063                   D0040PA00X+022870Y+015598               S0      
327NNAME00064                   D0040PA01X+020299Y-006391               S0      
317NNAME00064                   D0040PA00X+023264Y+013827               S0      
327NNAME00065                   D0040PA01X+020614Y-006391               S0      
317NNAME00065                   D0040PA00X+023657Y+013039               S0      
327NNAME00066                   D0040PA06X+020614Y-006391               S0      
317NNAME00066                   D0040PA00X+024051Y+014811               S0      
327NNAME00067                   D0040PA06X+020929Y-006391               S0      
317NNAME00067                   D0040PA00X+024445Y+015598               S0      
327NNAME00068                   D0040PA01X+021244Y-006391               S0      
317NNAME00068                   D0040PA00X+025626Y+013827               S0      
327NNAME00069                   D0040PA01X+021559Y-006391               S0      
317NNAME00069                   D0040PA00X+026020Y+013039               S0      
327NNAME00070                   D0040PA06X+021559Y-006391               S0      
317NNAME00070                   D0040PA00X+026413Y+014811               S0      
327NNAME00071                   D0040PA06X+021874Y-006391               S0      
317NNAME00071                   D0040PA00X+026807Y+015598               S0      
327NNAME00072                   D0040PA01X+022189Y-006391               S0      
317NNAME00072                   D0040PA00X+027201Y+013827               S0      
327NNAME00073                   D0040PA01X+022504Y-006391               S0      
317NNAME00073                   D0040PA00X+027594Y+013039               S0      
327NNAME00074                   D0040PA06X+022504Y-006391               S0      
317NNAME00074                   D0040PA00X+027988Y+014811               S0      
327NNAME00075                   D0040PA06X+022819Y-006391               S0      
317NNAME00075                   D0040PA00X+028382Y+015598               S0      
327NNAME00076                   D0040PA01X+023134Y-006391               S0      
317NNAME00076                   D0040PA00X+028776Y+013827               S0      
327NNAME00077                   D0040PA01X+023449Y-006391               S0      
317NNAME00077                   D0040PA00X+029169Y+013039               S0      
327NNAME00078                   D0040PA06X+023449Y-006391               S0      
317NNAME00078                   D0040PA00X+029563Y+014811               S0      
327NNAME00079                   D0040PA06X+023764Y-006391               S0      
317NNAME00079                   D0040PA00X+029957Y+015598               S0      
327NNAME00080                   D0040PA01X+024079Y-006391               S0      
317NNAME00080                   D0040PA00X+030350Y+013827               S0      
327NNAME00081                   D0040PA01X+024394Y-006391               S0      
317NNAME00081                   D0040PA00X+030744Y+013039               S0      
327NNAME00082                   D0040PA06X+024394Y-006391               S0      
317NNAME00082                   D0040PA00X+031138Y+014811               S0      
327NNAME00083                   D0040PA06X+024709Y-006391               S0      
317NNAME00083                   D0040PA00X+031531Y+015598               S0      
327NNAME00084                   D0040PA01X+025024Y-006391               S0      
317NNAME00084                   D0040PA00X+032319Y+013039               S0      
327NNAME00085                   D0040PA01X+025339Y-006391               S0      
317NNAME00085                   D0040PA00X+032713Y+013827               S0      
327NNAME00086                   D0040PA06X+025339Y-006391               S0      
317NNAME00086                   D0040PA00X+033106Y+015598               S0      
327NNAME00087                   D0040PA06X+025654Y-006391               S0      
317NNAME00087                   D0040PA00X+033500Y+014811               S0      
327NNAME00088                   D0040PA01X+025969Y-006391               S0      
317NNAME00088                   D0040PA00X+033894Y+013039               S0      
327NNAME00089                   D0040PA01X+026284Y-006391               S0      
317NNAME00089                   D0040PA00X+034287Y+013827               S0      
327NNAME00090                   D0040PA06X+026284Y-006391               S0      
317NNAME00090                   D0040PA00X+034681Y+015598               S0      
327NNAME00091                   D0040PA06X+026599Y-006391               S0      
317NNAME00091                   D0040PA00X+035075Y+014811               S0      
327NNAME00092                   D0040PA01X+026913Y-006391               S0      
317NNAME00092                   D0040PA00X+035468Y+013039               S0      
327NNAME00093                   D0040PA01X+027228Y-006391               S0      
317NNAME00093                   D0040PA00X+035862Y+013827               S0      
327NNAME00094                   D0040PA06X+027228Y-006391               S0      
317NNAME00094                   D0040PA00X+036256Y+015598               S0      
327NNAME00095                   D0040PA06X+027543Y-006391               S0      
317NNAME00095                   D0040PA00X+036650Y+014811               S0      
327NNAME00096                   D0040PA01X+027858Y-006391               S0      
317NNAME00096                   D0040PA00X+037043Y+013039               S0      
327NNAME00097                   D0040PA01X+028173Y-006391               S0      
317NNAME00097                   D0040PA00X+037437Y+013827               S0      
327NNAME00098                   D0040PA06X+028173Y-006391               S0      
317NNAME00098                   D0040PA00X+037831Y+015598               S0      
327NNAME00099                   D0040PA06X+028488Y-006391               S0      
317NNAME00099                   D0040PA00X+038224Y+014811               S0      
327NNAME00100                   D0040PA01X+028803Y-006391               S0      
317NNAME00100                   D0040PA00X+038618Y+013039               S0      
327NNAME00101                   D0040PA01X+029118Y-006391               S0      
317NNAME00101                   D0040PA00X+039012Y+013827               S0      
327NNAME00102                   D0040PA06X+029118Y-006391               S0      
317NNAME00102                   D0040PA00X+039405Y+015598               S0      
327NNAME00103                   D0040PA06X+029433Y-006391               S0      
317NNAME00103                   D0040PA00X+039799Y+014811               S0      
327NNAME00104                   D0040PA01X+029748Y-006391               S0      
317NNAME00104                   D0040PA00X+040193Y+013039               S0      
327NNAME00105                   D0040PA01X+030063Y-006391               S0      
317NNAME00105                   D0040PA00X+040587Y+013827               S0      
327NNAME00106                   D0040PA06X+030063Y-006391               S0      
317NNAME00106                   D0040PA00X+040980Y+015598               S0      
327NNAME00107                   D0040PA06X+030378Y-006391               S0      
317NNAME00107                   D0040PA00X+041374Y+014811               S0      
327NNAME00108                   D0040PA01X+030693Y-006391               S0      
317NNAME00108                   D0040PA00X+041768Y+013039               S0      
327NNAME00109                   D0040PA01X+031008Y-006391               S0      
317NNAME00109                   D0040PA00X+042161Y+013827               S0      
327NNAME00110                   D0040PA06X+031008Y-006391               S0      
317NNAME00110                   D0040PA00X+042555Y+015598               S0      
327NNAME00111                   D0040PA06X+031323Y-006391               S0      
317NNAME00111                   D0040PA00X+042949Y+014811               S0      
327NNAME00112                   D0040PA01X+031638Y-006391               S0      
317NNAME00112                   D0040PA00X+043342Y+013039               S0      
327NNAME00113                   D0040PA01X+031953Y-006391               S0      
317NNAME00113                   D0040PA00X+043736Y+013827               S0      
327NNAME00114                   D0040PA06X+031953Y-006391               S0      
317NNAME00114                   D0040PA00X+044130Y+015598               S0      
327NNAME00115                   D0040PA06X+032268Y-006391               S0      
317NNAME00115                   D0040PA00X+044524Y+014811               S0      
317NNAME00116                   D0040PA00X+018146Y+021039               S0      
327NNAME00116                   D0040PA01X+032583Y-006391               S0      
317NNAME00116       VIA        MD0040PA00X+032002Y-004646               S0      
317NNAME00117                   D0040PA00X+018539Y+021827               S0      
327NNAME00117                   D0040PA01X+032898Y-006391               S0      
317NNAME00117       VIA        MD0040PA00X+032402Y-004646               S0      
317NNAME00118                   D0040PA00X+018933Y+023598               S0      
327NNAME00118                   D0040PA06X+032898Y-006391               S0      
317NNAME00118       VIA        MD0040PA00X+032524Y-003648               S0      
317NNAME00119                   D0040PA00X+019327Y+022811               S0      
327NNAME00119                   D0040PA06X+033213Y-006391               S0      
317NNAME00119       VIA        MD0040PA00X+032924Y-003648               S0      
317NNAME00120                   D0040PA00X+020114Y+021827               S0      
327NNAME00120                   D0040PA01X+033528Y-006391               S0      
317NNAME00120       VIA        MD0040PA00X+033022Y-004646               S0      
317NNAME00121                   D0040PA00X+020508Y+021039               S0      
327NNAME00121                   D0040PA01X+033843Y-006391               S0      
317NNAME00121       VIA        MD0040PA00X+033422Y-004646               S0      
317NNAME00122                   D0040PA00X+020902Y+022811               S0      
327NNAME00122                   D0040PA06X+033843Y-006391               S0      
317NNAME00122       VIA        MD0040PA00X+033544Y-003648               S0      
317NNAME00123                   D0040PA00X+021295Y+023598               S0      
327NNAME00123                   D0040PA06X+034157Y-006391               S0      
317NNAME00123       VIA        MD0040PA00X+033944Y-003648               S0      
317NNAME00124                   D0040PA00X+021689Y+021827               S0      
327NNAME00124                   D0040PA01X+034473Y-006391               S0      
317NNAME00124       VIA        MD0040PA00X+034042Y-004646               S0      
317NNAME00125                   D0040PA00X+022083Y+021039               S0      
327NNAME00125                   D0040PA01X+034787Y-006391               S0      
317NNAME00125       VIA        MD0040PA00X+034442Y-004646               S0      
317NNAME00126                   D0040PA00X+022476Y+022811               S0      
327NNAME00126                   D0040PA06X+034787Y-006391               S0      
317NNAME00126       VIA        MD0040PA00X+034564Y-003648               S0      
317NNAME00127                   D0040PA00X+022870Y+023598               S0      
327NNAME00127                   D0040PA06X+035102Y-006391               S0      
317NNAME00127       VIA        MD0040PA00X+034964Y-003648               S0      
317NNAME00128                   D0040PA00X+023264Y+021827               S0      
327NNAME00128                   D0040PA01X+035417Y-006391               S0      
317NNAME00128       VIA        MD0040PA00X+035062Y-004646               S0      
317NNAME00129                   D0040PA00X+023657Y+021039               S0      
327NNAME00129                   D0040PA01X+035732Y-006391               S0      
317NNAME00129       VIA        MD0040PA00X+035462Y-004646               S0      
317NNAME00130                   D0040PA00X+024051Y+022811               S0      
327NNAME00130                   D0040PA06X+035732Y-006391               S0      
317NNAME00130       VIA        MD0040PA00X+035584Y-003648               S0      
317NNAME00131                   D0040PA00X+024445Y+023598               S0      
327NNAME00131                   D0040PA06X+036047Y-006391               S0      
317NNAME00131       VIA        MD0040PA00X+035984Y-003648               S0      
317NNAME00132                   D0040PA00X+025626Y+021827               S0      
327NNAME00132                   D0040PA01X+036362Y-006391               S0      
317NNAME00132       VIA        MD0040PA00X+036082Y-004646               S0      
317NNAME00133                   D0040PA00X+026020Y+021039               S0      
327NNAME00133                   D0040PA01X+036677Y-006391               S0      
317NNAME00133       VIA        MD0040PA00X+036482Y-004646               S0      
317NNAME00134                   D0040PA00X+026413Y+022811               S0      
327NNAME00134                   D0040PA06X+036677Y-006391               S0      
317NNAME00134       VIA        MD0040PA00X+036604Y-003648               S0      
317NNAME00135                   D0040PA00X+026807Y+023598               S0      
327NNAME00135                   D0040PA06X+036992Y-006391               S0      
317NNAME00135       VIA        MD0040PA00X+037004Y-003648               S0      
317NNAME00136                   D0040PA00X+027201Y+021827               S0      
327NNAME00136                   D0040PA01X+037307Y-006391               S0      
317NNAME00136       VIA        MD0040PA00X+037102Y-004646               S0      
317NNAME00137                   D0040PA00X+027594Y+021039               S0      
327NNAME00137                   D0040PA01X+037622Y-006391               S0      
317NNAME00137       VIA        MD0040PA00X+037502Y-004646               S0      
317NNAME00138                   D0040PA00X+027988Y+022811               S0      
327NNAME00138                   D0040PA06X+037622Y-006391               S0      
317NNAME00138       VIA        MD0040PA00X+037624Y-003648               S0      
317NNAME00139                   D0040PA00X+028382Y+023598               S0      
327NNAME00139                   D0040PA06X+037937Y-006391               S0      
317NNAME00139       VIA        MD0040PA00X+038024Y-003648               S0      
317NNAME00140                   D0040PA00X+028776Y+021827               S0      
327NNAME00140                   D0040PA01X+038252Y-006391               S0      
317NNAME00140       VIA        MD0040PA00X+038122Y-004646               S0      
317NNAME00141                   D0040PA00X+029169Y+021039               S0      
327NNAME00141                   D0040PA01X+038567Y-006391               S0      
317NNAME00141       VIA        MD0040PA00X+038522Y-004646               S0      
317NNAME00142                   D0040PA00X+029563Y+022811               S0      
327NNAME00142                   D0040PA06X+038567Y-006391               S0      
317NNAME00142       VIA        MD0040PA00X+038644Y-003648               S0      
317NNAME00143                   D0040PA00X+029957Y+023598               S0      
327NNAME00143                   D0040PA06X+038882Y-006391               S0      
317NNAME00143       VIA        MD0040PA00X+039044Y-003648               S0      
317NNAME00144                   D0040PA00X+030350Y+021827               S0      
327NNAME00144                   D0040PA01X+039197Y-006391               S0      
317NNAME00144       VIA        MD0040PA00X+039142Y-004646               S0      
317NNAME00145                   D0040PA00X+030744Y+021039               S0      
327NNAME00145                   D0040PA01X+039512Y-006391               S0      
317NNAME00145       VIA        MD0040PA00X+039542Y-004646               S0      
317NNAME00146                   D0040PA00X+031138Y+022811               S0      
327NNAME00146                   D0040PA06X+039512Y-006391               S0      
317NNAME00146       VIA        MD0040PA00X+039664Y-003648               S0      
317NNAME00147                   D0040PA00X+031531Y+023598               S0      
327NNAME00147                   D0040PA06X+039827Y-006391               S0      
317NNAME00147       VIA        MD0040PA00X+040064Y-003648               S0      
327FM_PRSNT_2_6_N               D0040PA01X+040142Y-006391               S0      
317FM_PRSNT_2_6_N               D0040PA01X+041145Y-000100               S0      
317FM_PRSNT_2_6_N   VIA        MD0040PA01X+041145Y-000833               S0      
327P3V3_VIN                     D0040PA01X+003560Y+007550               S0      
327P3V3_VIN                     D0040PA01X+006310Y+008200               S0      
327P3V3_VIN                     D0040PA06X+005582Y+007523               S0      
327P3V3_VIN                     D0040PA06X+005582Y+006437               S0      
317P3V3_VIN                     D0040PA06X+005257Y+005618               S0      
327P3V3_VIN                     D0040PA06X+006270Y+008560               S0      
317P3V3_VIN         VIA        MD0040PA06X+005530Y+008660               S0      
317P3V3_VIN         VIA        MD0040PA00X+004940Y+006000               S0      
317P3V3_VIN         VIA        MD0040PA00X+005070Y+008190               S0      
317P3V3_VIN         VIA        MD0040PA00X+005300Y+005980               S0      
317P3V3_VIN         VIA        MD0040PA00X+005430Y+008170               S0      
317P3V3_VIN         VIA        MD0040PA00X+005800Y+008160               S0      
317P3V3_FB                      D0040PA06X+003460Y+007900               S0      
327P3V3_FB                      D0040PA06X+005156Y+007295               S0      
317P3V3_FB                      D0040PA06X+003470Y+008290               S0      
317P3V3_FB                      D0040PA06X+004450Y+007420               S0      
317P3V3_VFB_R                   D0040PA06X+003120Y+007900               S0      
317P3V3_VFB_R                   D0040PA06X+003110Y+008290               S0      
317P3V3_VFB_R                   D0040PA06X+002440Y+006540               S0      
327P3V3_TRK                     D0040PA06X+005156Y+006980               S0      
317P3V3_TRK                     D0040PA06X+003650Y+007130               S0      
317P3V3_TRK                     D0040PA06X+003230Y+007490               S0      
317P3V3_TRK         VIA        MD0040PA06X+002780Y+007530               S0      
327AGND_P3V3                    D0040PA06X+005156Y+006508               S0      
317AGND_P3V3                    D0040PA06X+003090Y+006255               S0      
317AGND_P3V3                    D0040PA06X+003680Y+005980               S0      
317AGND_P3V3                    D0040PA06X+003230Y+007130               S0      
317AGND_P3V3                    D0040PA06X+003270Y+006730               S0      
317AGND_P3V3        VIA        MD0040PA06X+002800Y+006980               S0      
327P3V3_VCC                     D0040PA06X+006244Y+006311               S0      
317P3V3_VCC                     D0040PA06X+007530Y+006000               S0      
317P3V3_VCC                     D0040PA06X+007080Y+006010               S0      
317P3V3_VCC         VIA        MD0040PA06X+007960Y+006390               S0      
327P3V3_EN                      D0040PA06X+005156Y+007452               S0      
317P3V3_EN                      D0040PA06X+004210Y+009100               S0      
317P3V3_EN                      D0040PA06X+003920Y+008520               S0      
317P3V3_EN                      D0040PA06X+003960Y+008070               S0      
317P3V3_EN          VIA        MD0040PA06X+004595Y+009313               S0      
327P3V3_BST                     D0040PA06X+005166Y+006311               S0      
317P3V3_BST                     D0040PA06X+004090Y+005510               S0      
327P3V3_SW                      D0040PA06X+005818Y+006437               S0      
317P3V3_SW                      D0040PA06X+004090Y+004950               S0      
327P3V3_SW                      D0040PA06X+005840Y+004724               S0      
317P3V3_VR                      D0040PA01X+008540Y+004280               S0      
327P3V3_VR                      D0040PA01X+009270Y+003440               S0      
327P3V3_VR                      D0040PA06X+007740Y+004190               S0      
327P3V3_VR                      D0040PA06X+008510Y+004190               S0      
327P3V3_VR                      D0040PA06X+008510Y+003070               S0      
327P3V3_VR                      D0040PA06X+005840Y+002516               S0      
327P3V3_VR                      D0040PA06X+007740Y+003070               S0      
317P3V3_VR                      D0040PA06X+002440Y+005980               S0      
317P3V3_VR          VIA        MD0040PA06X+002640Y+004290               S0      
317P3V3_VR          VIA        MD0040PA00X+006930Y+003650               S0      
317P3V3_VR          VIA        MD0040PA00X+006940Y+002670               S0      
317P3V3_VR          VIA        MD0040PA00X+007150Y+003950               S0      
317P3V3_VR          VIA        MD0040PA00X+007170Y+003150               S0      
317P3V3_VR          VIA        MD0040PA00X+007460Y+003610               S0      
317P3V3_VR          VIA        MD0040PA00X+007860Y+003620               S0      
317P3V3_VR          VIA        MD0040PA00X+008230Y+003620               S0      
317P3V3_VR          VIA        MD0040PA00X+008600Y+003609               S0      
317P3V3_PG                      D0040PA01X+009950Y+005260               S0      
327P3V3_PG                      D0040PA06X+005156Y+007649               S0      
317P3V3_PG                      D0040PA06X+007870Y+006000               S0      
317P3V3_PG          VIA        MD0040PA06X+005160Y+008990               S0      
317P3V3_PG          VIA        MD0040PA00X+004880Y+008710               S0      
317P3V3_PG          VIA        MD0040PA00X+008320Y+006000               S0      
327P3V3_MODE                    D0040PA06X+005156Y+006823               S0      
317P3V3_MODE                    D0040PA06X+003610Y+006730               S0      
317P3V3_MODE        VIA        MD0040PA06X+003970Y+006640               S0      
327P3V3_CS                      D0040PA06X+005156Y+006665               S0      
317P3V3_CS                      D0040PA06X+003680Y+006320               S0      
317P3V3_CS          VIA        MD0040PA06X+004450Y+006450               S0      
327NNAME00148                   D0040PA01X+028214Y+018882               S0      
317NNAME00148                   D0040PA01X+029340Y+018780               S0      
327NNAME00148                   D0040PA01X+015315Y-000004               S0      
317NNAME00148       VIA        MD0040PA06X+015660Y+000490               S0      
317NNAME00148       VIA        MD0040PA00X+016040Y+000490               S0      
317NNAME00148       VIA        MD0040PA00X+019990Y+016160               S0      
317SMB_PCH_ALERT                D0040PA01X+015630Y+001520               S0      
327SMB_PCH_ALERT                D0040PA01X+015315Y+000736               S0      
327SMB_PCH_ALERT                D0040PA01X+015059Y+000736               S0      
317SMB_PCH_ALERT    VIA        MD0040PA01X+015180Y+001310               S0      
327PU_B_MUX_SDA2                D0040PA01X+008668Y+019584               S0      
317PU_B_MUX_SDA2                D0040PA01X+009170Y+020700               S0      
317PU_B_MUX_SDA2    VIA        MD0040PA01X+008994Y+020283               S0      
317NNAME00149                   D0040PA01X+054120Y+017213               S0      
327NNAME00149                   D0040PA01X+052487Y+017560               S0      
317NNAME00149       VIA        MD0040PA01X+053760Y+016910               S0      
317NNAME00150                   D0040PA01X+012100Y+011117               S0      
317NNAME00150                   D0040PA01X+010107Y+014891               S0      
317NNAME00150                   D0040PA01X+054460Y+017213               S0      
317NNAME00150                   D0040PA01X+038180Y+003420               S0      
327NNAME00150                   D0040PA01X+007900Y+019584               S0      
317NNAME00150                   D0040PA01X+039515Y+006956               S0      
317NNAME00150                   D0040PA01X+007950Y+020700               S0      
317NNAME00150       VIA        MD0040PA06X+054420Y+016950               S0      
317NNAME00150       VIA        MD0040PA00X+010650Y+014900               S0      
317NNAME00150       VIA        MD0040PA00X+012170Y+011730               S0      
317NNAME00150       VIA        MD0040PA00X+038801Y+003771               S0      
317NNAME00150       VIA        MD0040PA00X+039541Y+006609               S0      
317NNAME00150       VIA        MD0040PA00X+055138Y+017202               S0      
317NNAME00150       VIA        MD0040PA00X+007984Y+020268               S0      
317NNAME00151                   D0040PA01X+054120Y+017616               S0      
327NNAME00151                   D0040PA01X+052803Y+017875               S0      
317NNAME00151       VIA        MD0040PA01X+053470Y+017320               S0      
317NNAME00152                   D0040PA01X+054460Y+017616               S0      
327NNAME00152                   D0040PA01X+007644Y+019584               S0      
317NNAME00152                   D0040PA01X+010104Y+015324               S0      
317NNAME00152                   D0040PA01X+011667Y+011117               S0      
317NNAME00152                   D0040PA01X+007550Y+020700               S0      
317NNAME00152                   D0040PA01X+039932Y+006956               S0      
317NNAME00152                   D0040PA01X+038180Y+003010               S0      
317NNAME00152       VIA        MD0040PA06X+055530Y+017270               S0      
317NNAME00152       VIA        MD0040PA00X+010540Y+015360               S0      
317NNAME00152       VIA        MD0040PA00X+011760Y+011770               S0      
317NNAME00152       VIA        MD0040PA00X+039120Y+003570               S0      
317NNAME00152       VIA        MD0040PA00X+039881Y+006620               S0      
317NNAME00152       VIA        MD0040PA00X+055138Y+017627               S0      
317NNAME00152       VIA        MD0040PA00X+007559Y+020268               S0      
327NNAME00153                   D0040PA01X+034464Y+006037               S0      
327NNAME00153                   D0040PA01X+034144Y+002337               S0      
317NNAME00153                   D0040PA01X+019401Y+011700               S0      
317NNAME00153                   D0040PA00X+019327Y+013827               S0      
317NNAME00153       VIA        MD0040PA01X+019950Y+009810               S0      
317NNAME00153       VIA        MD0040PA00X+019940Y+008140               S0      
317NNAME00153       VIA        MD0040PA00X+034352Y+003697               S0      
317NNAME00153       VIA        MD0040PA00X+034970Y+006420               S0      
327NNAME00154                   D0040PA01X+034464Y+005781               S0      
327NNAME00154                   D0040PA01X+034144Y+002081               S0      
317NNAME00154                   D0040PA01X+024140Y+011760               S0      
317NNAME00154                   D0040PA00X+024839Y+013827               S0      
317NNAME00154       VIA        MD0040PA06X+023840Y+008930               S0      
317NNAME00154       VIA        MD0040PA00X+023690Y+008580               S0      
317NNAME00154       VIA        MD0040PA00X+034600Y+003464               S0      
317NNAME00154       VIA        MD0040PA00X+035310Y+006390               S0      
327NNAME00155                   D0040PA01X+034464Y+005525               S0      
317NNAME00155                   D0040PA01X+030650Y+011640               S0      
327NNAME00155                   D0040PA01X+034144Y+001825               S0      
317NNAME00155                   D0040PA00X+031531Y+013039               S0      
317NNAME00155       VIA        MD0040PA06X+035130Y+008200               S0      
317NNAME00155       VIA        MD0040PA00X+030080Y+010010               S0      
317NNAME00155       VIA        MD0040PA00X+034900Y+002830               S0      
317NNAME00155       VIA        MD0040PA00X+034970Y+005600               S0      
317NNAME00155       VIA        MD0040PA00X+035530Y+008140               S0      
327NNAME00156                   D0040PA01X+034464Y+005013               S0      
327NNAME00156                   D0040PA01X+034144Y+001313               S0      
317NNAME00156                   D0040PA00X+019327Y+021827               S0      
317NNAME00156                   D0040PA01X+016815Y+019833               S0      
317NNAME00156       VIA        MD0040PA06X+018390Y+018990               S0      
317NNAME00156       VIA        MD0040PA00X+017990Y+019130               S0      
317NNAME00156       VIA        MD0040PA00X+033200Y+019220               S0      
317NNAME00156       VIA        MD0040PA00X+035150Y+003610               S0      
317NNAME00156       VIA        MD0040PA00X+035214Y+005073               S0      
317NNAME00157                   D0040PA01X+022663Y+019520               S0      
327NNAME00157                   D0040PA01X+034464Y+004757               S0      
327NNAME00157                   D0040PA01X+034144Y+001057               S0      
317NNAME00157                   D0040PA00X+024839Y+021827               S0      
317NNAME00157       VIA        MD0040PA00X+022410Y+020010               S0      
317NNAME00157       VIA        MD0040PA00X+032940Y+019590               S0      
317NNAME00157       VIA        MD0040PA00X+035270Y+004000               S0      
317NNAME00157       VIA        MD0040PA00X+035554Y+005059               S0      
327NNAME00158                   D0040PA01X+034464Y+004501               S0      
327NNAME00158                   D0040PA01X+034144Y+000801               S0      
317NNAME00158                   D0040PA00X+031531Y+021039               S0      
317NNAME00158                   D0040PA01X+030551Y+019801               S0      
317NNAME00158       VIA        MD0040PA06X+035050Y+004660               S0      
317NNAME00158       VIA        MD0040PA00X+033479Y+019529               S0      
317NNAME00158       VIA        MD0040PA00X+035530Y+003390               S0      
317NNAME00158       VIA        MD0040PA00X+035540Y+004719               S0      
327NNAME00159                   D0040PA01X+034464Y+005269               S0      
327NNAME00159                   D0040PA01X+034144Y+001569               S0      
317NNAME00159                   D0040PA01X+043670Y+011600               S0      
317NNAME00159                   D0040PA00X+044524Y+013827               S0      
317NNAME00159       VIA        MD0040PA06X+035390Y+002990               S0      
317NNAME00159       VIA        MD0040PA00X+035030Y+003180               S0      
317NNAME00159       VIA        MD0040PA00X+035310Y+005588               S0      
317NNAME00159       VIA        MD0040PA00X+035670Y+008660               S0      
317PU_B_MUX_SCL2                D0040PA01X+008750Y+020700               S0      
327PU_B_MUX_SCL2                D0040PA01X+008412Y+019584               S0      
317PU_B_MUX_SCL2    VIA        MD0040PA01X+008440Y+020280               S0      
327GPIO_B_EXP_A0                D0040PA01X+036364Y+002337               S0      
317GPIO_B_EXP_A0                D0040PA01X+037370Y+002560               S0      
317GPIO_B_EXP_A0                D0040PA01X+037370Y+002150               S0      
317GPIO_B_EXP_A0    VIA        MD0040PA01X+036990Y+002337               S0      
327GPIO_B_EXP_A2                D0040PA01X+034144Y+002593               S0      
317GPIO_B_EXP_A2                D0040PA01X+033040Y+002390               S0      
317GPIO_B_EXP_A2                D0040PA01X+033040Y+001970               S0      
317GPIO_B_EXP_A2    VIA        MD0040PA01X+033470Y+002437               S0      
317GPIO_B_EXP_A1                D0040PA01X+033150Y+003160               S0      
327GPIO_B_EXP_A1                D0040PA01X+034144Y+002849               S0      
317GPIO_B_EXP_A1                D0040PA01X+032780Y+003590               S0      
317GPIO_B_EXP_A1    VIA        MD0040PA01X+033510Y+003140               S0      
327GPIO_P_EXP_A2                D0040PA01X+034464Y+006293               S0      
317GPIO_P_EXP_A2                D0040PA01X+033620Y+005630               S0      
317GPIO_P_EXP_A2                D0040PA01X+033620Y+005220               S0      
317GPIO_P_EXP_A2    VIA        MD0040PA01X+033420Y+004770               S0      
327GPIO_P_EXP_A0                D0040PA01X+036684Y+006037               S0      
317GPIO_P_EXP_A0                D0040PA01X+037660Y+006540               S0      
317GPIO_P_EXP_A0                D0040PA01X+037660Y+006950               S0      
317GPIO_P_EXP_A0    VIA        MD0040PA01X+038070Y+007440               S0      
317GPIO_B_IO1_0                 D0040PA01X+037330Y-000120               S0      
327GPIO_B_IO1_0                 D0040PA01X+036364Y+000289               S0      
317GPIO_B_IO1_0                 D0040PA01X+036360Y-000180               S0      
317GPIO_B_IO1_0     VIA        MD0040PA01X+036870Y-000153               S0      
317SMB_B_HUB_A0                 D0040PA01X+005590Y+021040               S0      
327SMB_B_HUB_A0                 D0040PA01X+006620Y+017364               S0      
317SMB_B_HUB_A0                 D0040PA01X+005930Y+017680               S0      
317SMB_B_HUB_A0     VIA        MD0040PA01X+006040Y+018770               S0      
317NNAME00160                   D0040PA01X+017130Y+018620               S0      
327NNAME00160                   D0040PA01X+034464Y+004245               S0      
327NNAME00160                   D0040PA01X+034144Y+000545               S0      
317NNAME00160                   D0040PA00X+044524Y+021827               S0      
317NNAME00160       VIA        MD0040PA06X+018450Y+018480               S0      
317NNAME00160       VIA        MD0040PA00X+018030Y+018720               S0      
317NNAME00160       VIA        MD0040PA00X+035537Y+003741               S0      
317NNAME00160       VIA        MD0040PA00X+035902Y+004718               S0      
317NNAME00160       VIA        MD0040PA00X+045570Y+020580               S0      
317GPIO_B_IO1_3                 D0040PA01X+037350Y+000740               S0      
327GPIO_B_IO1_3                 D0040PA01X+036364Y+001057               S0      
317GPIO_B_IO1_3                 D0040PA01X+037350Y+000330               S0      
317GPIO_B_IO1_3     VIA        MD0040PA01X+036990Y+000730               S0      
317GPIO_B_IO1_4                 D0040PA01X+038720Y+000740               S0      
317GPIO_B_IO1_4                 D0040PA01X+038720Y+000330               S0      
327GPIO_B_IO1_4                 D0040PA01X+036364Y+001313               S0      
317GPIO_B_IO1_4     VIA        MD0040PA01X+039110Y+000450               S0      
327GPIO_B_IO1_5                 D0040PA01X+036364Y+001569               S0      
317GPIO_B_IO1_5                 D0040PA01X+038710Y+001730               S0      
317GPIO_B_IO1_5                 D0040PA01X+038710Y+001320               S0      
317GPIO_B_IO1_5     VIA        MD0040PA01X+036970Y+001270               S0      
317GPIO_B_IO1_6                 D0040PA01X+037368Y+001332               S0      
327GPIO_B_IO1_6                 D0040PA01X+036364Y+001825               S0      
317GPIO_B_IO1_6                 D0040PA01X+037369Y+001737               S0      
317GPIO_B_IO1_6     VIA        MD0040PA01X+036948Y+001750               S0      
317SMB_B_HUB_A1                 D0040PA01X+005970Y+016830               S0      
327SMB_B_HUB_A1                 D0040PA01X+006876Y+017364               S0      
317SMB_B_HUB_A1                 D0040PA01X+005970Y+017240               S0      
317SMB_B_HUB_A1     VIA        MD0040PA01X+006340Y+016830               S0      
327GPIO_B_IO1_7                 D0040PA01X+036364Y+002081               S0      
317GPIO_B_IO1_7                 D0040PA01X+038710Y+002170               S0      
317GPIO_B_IO1_7                 D0040PA01X+038710Y+002580               S0      
317GPIO_B_IO1_7     VIA        MD0040PA01X+038780Y+002980               S0      
317GPIO_P_IO1_0                 D0040PA01X+037670Y+003840               S0      
327GPIO_P_IO1_0                 D0040PA01X+036684Y+003989               S0      
317GPIO_P_IO1_0                 D0040PA01X+037680Y+004250               S0      
317GPIO_P_IO1_0     VIA        MD0040PA01X+037300Y+004490               S0      
327GPIO_P_IO1_3                 D0040PA01X+036684Y+004757               S0      
317GPIO_P_IO1_3                 D0040PA01X+037680Y+004660               S0      
317GPIO_P_IO1_3                 D0040PA01X+037680Y+005070               S0      
317GPIO_P_IO1_3     VIA        MD0040PA01X+037290Y+005000               S0      
327GPIO_P_IO1_4                 D0040PA01X+036684Y+005013               S0      
317GPIO_P_IO1_4                 D0040PA01X+039020Y+004660               S0      
317GPIO_P_IO1_4                 D0040PA01X+039020Y+005070               S0      
317GPIO_P_IO1_4     VIA        MD0040PA01X+039377Y+004810               S0      
317GPIO_P_IO1_5                 D0040PA01X+037682Y+005962               S0      
327GPIO_P_IO1_5                 D0040PA01X+036684Y+005269               S0      
317GPIO_P_IO1_5                 D0040PA01X+037681Y+005557               S0      
317GPIO_P_IO1_5     VIA        MD0040PA01X+037310Y+005560               S0      
327GPIO_P_IO1_6                 D0040PA01X+036684Y+005525               S0      
317GPIO_P_IO1_6                 D0040PA01X+039020Y+005960               S0      
317GPIO_P_IO1_6                 D0040PA01X+039020Y+005550               S0      
317GPIO_P_IO1_6     VIA        MD0040PA01X+039390Y+005790               S0      
327GPIO_P_EXP_A1                D0040PA01X+034464Y+006549               S0      
317GPIO_P_EXP_A1                D0040PA01X+033620Y+006040               S0      
317GPIO_P_EXP_A1                D0040PA01X+033410Y+006470               S0      
317GPIO_P_EXP_A1    VIA        MD0040PA01X+033810Y+006540               S0      
327GPIO_P_IO1_7                 D0040PA01X+036684Y+005781               S0      
317GPIO_P_IO1_7                 D0040PA01X+039030Y+006950               S0      
317GPIO_P_IO1_7                 D0040PA01X+039030Y+006540               S0      
317GPIO_P_IO1_7     VIA        MD0040PA01X+038980Y+007350               S0      
317NNAME00161                   D0040PA01X+052160Y+016580               S0      
327NNAME00161                   D0040PA01X+051897Y+017560               S0      
317NNAME00161                   D0040PA01X+051753Y+016580               S0      
317NNAME00161       VIA        MD0040PA01X+051510Y+016950               S0      
317SMB_B_HUB_A2                 D0040PA01X+006340Y+015760               S0      
317SMB_B_HUB_A2                 D0040PA01X+005930Y+015770               S0      
327SMB_B_HUB_A2                 D0040PA01X+007132Y+017364               S0      
317SMB_B_HUB_A2     VIA        MD0040PA01X+006250Y+016170               S0      
317NNAME00162                   D0040PA01X+053016Y+016590               S0      
317NNAME00162                   D0040PA01X+052611Y+016590               S0      
327NNAME00162                   D0040PA01X+052094Y+017560               S0      
317NNAME00162       VIA        MD0040PA01X+052229Y+016977               S0      
327RESET_O_2_R                  D0040PA01X+011060Y+005945               S0      
317RESET_O_2_R                  D0040PA01X+010290Y+005260               S0      
317RESET_O_2_R                  D0040PA01X+010880Y+004910               S0      
317RESET_O_2_R      VIA        MD0040PA01X+010990Y+005300               S0      
327NNAME00163                   D0040PA01X+011078Y+009375               S0      
317NNAME00163                   D0040PA01X+011790Y+009801               S0      
317NNAME00163       VIA        MD0040PA06X+011880Y+009460               S0      
317NNAME00163       VIA        MD0040PA00X+011485Y+009565               S0      
317NNAME00164                   D0040PA01X+010522Y+014126               S0      
327NNAME00164                   D0040PA01X+008156Y+019584               S0      
317NNAME00164                   D0040PA01X+008350Y+020700               S0      
317NNAME00164                   D0040PA01X+033630Y+003930               S0      
317NNAME00164                   D0040PA01X+053435Y+016246               S0      
317NNAME00164                   D0040PA01X+012130Y+009801               S0      
317NNAME00164       VIA        MD0040PA06X+008350Y+019290               S0      
317NNAME00164       VIA        MD0040PA00X+010522Y+013722               S0      
317NNAME00164       VIA        MD0040PA00X+012440Y+010310               S0      
317NNAME00164       VIA        MD0040PA00X+033790Y+004680               S0      
317NNAME00164       VIA        MD0040PA00X+051790Y+010330               S0      
317NNAME00164       VIA        MD0040PA00X+008350Y+018900               S0      
317NNAME00165                   D0040PA01X+033210Y+003600               S0      
327NNAME00165                   D0040PA01X+034144Y+003105               S0      
317NNAME00165                   D0040PA01X+033630Y+003590               S0      
317NNAME00165       VIA        MD0040PA01X+033990Y+003570               S0      
317NNAME00166                   D0040PA01X+034570Y+008030               S0      
327NNAME00166                   D0040PA01X+028214Y+018114               S0      
317NNAME00166                   D0040PA01X+030110Y+017140               S0      
317NNAME00166       VIA        MD0040PA01X+029258Y+017987               S0      
317NNAME00166       VIA        MD0040PA00X+034615Y+008480               S0      
317NNAME00166       VIA        MD0040PA00X+034820Y+016990               S0      
317NNAME00167                   D0040PA01X+034570Y+007690               S0      
327NNAME00167                   D0040PA01X+034464Y+006805               S0      
317NNAME00167                   D0040PA01X+033780Y+006960               S0      
317NNAME00167       VIA        MD0040PA01X+034290Y+007320               S0      
317SMCLK_USB_HUB                D0040PA01X+042980Y+002650               S0      
317SMCLK_USB_HUB                D0040PA01X+039936Y+007820               S0      
317SMCLK_USB_HUB                D0040PA01X+039932Y+007296               S0      
327SMCLK_USB_HUB                D0040PA01X+039977Y+002859               S0      
317SMCLK_USB_HUB    VIA        MD0040PA06X+042650Y+002690               S0      
317SMCLK_USB_HUB    VIA        MD0040PA00X+040860Y+002738               S0      
317SMCLK_USB_HUB    VIA        MD0040PA00X+042985Y+002295               S0      
317NNAME00168                   D0040PA01X+030700Y+018220               S0      
317NNAME00168                   D0040PA01X+039936Y+008160               S0      
317NNAME00168                   D0040PA01X+037560Y+008170               S0      
327NNAME00168                   D0040PA01X+028214Y+018626               S0      
317NNAME00168       VIA        MD0040PA01X+031970Y+017820               S0      
317NNAME00168       VIA        MD0040PA00X+032720Y+017828               S0      
317NNAME00168       VIA        MD0040PA00X+037551Y+008500               S0      
317NNAME00168       VIA        MD0040PA00X+040250Y+008912               S0      
317SMDAT_USB_HUB                D0040PA01X+041870Y+002640               S0      
317SMDAT_USB_HUB                D0040PA01X+039513Y+007820               S0      
327SMDAT_USB_HUB                D0040PA01X+039721Y+002859               S0      
317SMDAT_USB_HUB                D0040PA01X+039515Y+007296               S0      
317SMDAT_USB_HUB    VIA        MD0040PA06X+041770Y+002780               S0      
317SMDAT_USB_HUB    VIA        MD0040PA00X+040860Y+002312               S0      
317SMDAT_USB_HUB    VIA        MD0040PA00X+041865Y+002285               S0      
317NNAME00169                   D0040PA01X+037150Y+008170               S0      
317NNAME00169                   D0040PA01X+030700Y+017810               S0      
317NNAME00169                   D0040PA01X+039513Y+008160               S0      
327NNAME00169                   D0040PA01X+028214Y+018370               S0      
317NNAME00169       VIA        MD0040PA01X+031400Y+017840               S0      
317NNAME00169       VIA        MD0040PA00X+032720Y+017402               S0      
317NNAME00169       VIA        MD0040PA00X+037211Y+008500               S0      
317NNAME00169       VIA        MD0040PA00X+040250Y+009338               S0      
317NNAME00170                   D0040PA01X+010522Y+014466               S0      
327NNAME00170                   D0040PA01X+008529Y+014127               S0      
317NNAME00170       VIA        MD0040PA01X+009210Y+014370               S0      
327NNAME00171                   D0040PA01X+052290Y+017560               S0      
317NNAME00171                   D0040PA01X+053435Y+016586               S0      
317NNAME00171       VIA        MD0040PA01X+052880Y+017000               S0      
317NNAME00172                   D0040PA01X+024640Y+017650               S0      
317NNAME00172                   D0040PA01X+017532Y+017650               S0      
327NNAME00172                   D0040PA01X+025994Y+018370               S0      
317NNAME00172       VIA        MD0040PA06X+022140Y+017920               S0      
317NNAME00172       VIA        MD0040PA00X+018008Y+017988               S0      
317NNAME00172       VIA        MD0040PA00X+026750Y+018200               S0      
317NNAME00173                   D0040PA01X+017129Y+017650               S0      
327NNAME00173                   D0040PA01X+025994Y+018626               S0      
317NNAME00173                   D0040PA01X+024640Y+018060               S0      
317NNAME00173       VIA        MD0040PA06X+020980Y+018370               S0      
317NNAME00173       VIA        MD0040PA00X+018000Y+018350               S0      
317NNAME00173       VIA        MD0040PA00X+026600Y+018510               S0      
317SMCLK_PCH_R                  D0040PA01X+030200Y+018970               S0      
317SMCLK_PCH_R                  D0040PA01X+018518Y+017004               S0      
327SMCLK_PCH_R                  D0040PA01X+020066Y+018859               S0      
327SMCLK_PCH_R                  D0040PA01X+028214Y+019138               S0      
317SMCLK_PCH_R      VIA        MD0040PA01X+018669Y+018340               S0      
317SMDAT_PCH_R                  D0040PA01X+018115Y+017004               S0      
317SMDAT_PCH_R                  D0040PA01X+030200Y+019370               S0      
327SMDAT_PCH_R                  D0040PA01X+020322Y+018859               S0      
327SMDAT_PCH_R                  D0040PA01X+028214Y+019394               S0      
317SMDAT_PCH_R      VIA        MD0040PA01X+018579Y+018870               S0      
317NNAME00174                   D0040PA01X+023420Y+017140               S0      
317NNAME00174                   D0040PA01X+023010Y+017122               S0      
327NNAME00174                   D0040PA01X+025994Y+017602               S0      
317NNAME00174       VIA        MD0040PA01X+025170Y+017190               S0      
317NNAME00175                   D0040PA01X+023430Y+017570               S0      
327NNAME00175                   D0040PA01X+025994Y+017858               S0      
317NNAME00175                   D0040PA01X+023010Y+017555               S0      
317NNAME00175       VIA        MD0040PA01X+024210Y+017120               S0      
317PU_P_MUX_SCL2                D0040PA01X+029340Y+017180               S0      
327PU_P_MUX_SCL2                D0040PA01X+028214Y+017858               S0      
317PU_P_MUX_SCL2    VIA        MD0040PA01X+028900Y+017660               S0      
317PU_P_MUX_SDA2                D0040PA01X+029340Y+016760               S0      
327PU_P_MUX_SDA2                D0040PA01X+028214Y+017602               S0      
317PU_P_MUX_SDA2    VIA        MD0040PA01X+028960Y+017180               S0      
317SMB_P_HUB_A0                 D0040PA01X+023760Y+019440               S0      
317SMB_P_HUB_A0                 D0040PA01X+023760Y+019850               S0      
327SMB_P_HUB_A0                 D0040PA01X+025994Y+019650               S0      
317SMB_P_HUB_A0     VIA        MD0040PA06X+026070Y+019790               S0      
317SMB_P_HUB_A0     VIA        MD0040PA00X+025675Y+019970               S0      
327NNAME00176                   D0040PA01X+007644Y+017364               S0      
317NNAME00176                   D0040PA01X+007120Y+016380               S0      
317NNAME00176                   D0040PA01X+007173Y+015917               S0      
317NNAME00176       VIA        MD0040PA01X+007080Y+015200               S0      
317NNAME00177                   D0040PA00X+014209Y+013039               S0      
317NNAME00177                   D0040PA01X+007173Y+015577               S0      
317NNAME00177       VIA        MD0040PA01X+009320Y+015600               S0      
317NNAME00177       VIA        MD0040PA00X+011192Y+015672               S0      
317NNAME00178                   D0040PA01X+007530Y+016380               S0      
327NNAME00178                   D0040PA01X+007900Y+017364               S0      
317NNAME00178                   D0040PA01X+007580Y+015915               S0      
317NNAME00178       VIA        MD0040PA01X+007661Y+016752               S0      
317NNAME00179                   D0040PA01X+007580Y+015575               S0      
317NNAME00179                   D0040PA00X+013815Y+013827               S0      
317NNAME00179       VIA        MD0040PA01X+008840Y+015850               S0      
317NNAME00179       VIA        MD0040PA00X+011618Y+015672               S0      
317NNAME00180                   D0040PA01X+006750Y+015760               S0      
327NNAME00180                   D0040PA01X+007388Y+017364               S0      
327NNAME00180                   D0040PA01X+025994Y+018882               S0      
317NNAME00180                   D0040PA01X+018350Y+011850               S0      
317NNAME00180       VIA        MD0040PA06X+007150Y+017230               S0      
317NNAME00180       VIA        MD0040PA00X+018140Y+012450               S0      
317NNAME00180       VIA        MD0040PA00X+018170Y+007270               S0      
317NNAME00180       VIA        MD0040PA00X+025490Y+018830               S0      
317NNAME00180       VIA        MD0040PA00X+007150Y+016850               S0      
317NNAME00181                   D0040PA01X+018010Y+011850               S0      
317NNAME00181                   D0040PA00X+017358Y+013039               S0      
317NNAME00181       VIA        MD0040PA01X+018180Y+011050               S0      
317NNAME00182                   D0040PA01X+017129Y+017310               S0      
317NNAME00182                   D0040PA00X+014996Y+015598               S0      
317NNAME00182       VIA        MD0040PA06X+016880Y+016960               S0      
317NNAME00182       VIA        MD0040PA00X+017200Y+016680               S0      
317NNAME00183                   D0040PA01X+017532Y+017310               S0      
317NNAME00183                   D0040PA00X+014602Y+014811               S0      
317NNAME00183       VIA        MD0040PA06X+017380Y+017120               S0      
317NNAME00183       VIA        MD0040PA00X+017560Y+016680               S0      
317NNAME00184                   D0040PA01X+009570Y+016480               S0      
317NNAME00184                   D0040PA01X+010225Y+016431               S0      
327NNAME00184                   D0040PA01X+008412Y+017364               S0      
317NNAME00184       VIA        MD0040PA01X+008731Y+016343               S0      
317NNAME00185                   D0040PA01X+010565Y+016431               S0      
317NNAME00185                   D0040PA00X+014209Y+021039               S0      
317NNAME00185       VIA        MD0040PA06X+011360Y+016460               S0      
317NNAME00185       VIA        MD0040PA00X+010950Y+016450               S0      
317NNAME00186                   D0040PA01X+010225Y+016851               S0      
317NNAME00186                   D0040PA01X+009570Y+016890               S0      
327NNAME00186                   D0040PA01X+008668Y+017364               S0      
317NNAME00186       VIA        MD0040PA01X+008950Y+016770               S0      
317NNAME00187                   D0040PA01X+010565Y+016851               S0      
317NNAME00187                   D0040PA00X+013815Y+021827               S0      
317NNAME00187       VIA        MD0040PA06X+010540Y+016850               S0      
317NNAME00187       VIA        MD0040PA00X+010950Y+016875               S0      
327NNAME00188                   D0040PA01X+008156Y+017364               S0      
317NNAME00188                   D0040PA01X+017573Y+019830               S0      
317NNAME00188                   D0040PA01X+008330Y+016190               S0      
327NNAME00188                   D0040PA01X+025994Y+018114               S0      
317NNAME00188       VIA        MD0040PA06X+009600Y+019580               S0      
317NNAME00188       VIA        MD0040PA00X+017330Y+020497               S0      
317NNAME00188       VIA        MD0040PA00X+009600Y+019200               S0      
317NNAME00189                   D0040PA00X+017358Y+021039               S0      
317NNAME00189                   D0040PA01X+017233Y+019830               S0      
317NNAME00190                   D0040PA00X+014996Y+023598               S0      
317NNAME00190                   D0040PA01X+022670Y+017555               S0      
317NNAME00190       VIA        MD0040PA06X+018740Y+019590               S0      
317NNAME00190       VIA        MD0040PA00X+018368Y+019852               S0      
317NNAME00191                   D0040PA01X+022670Y+017122               S0      
317NNAME00191                   D0040PA00X+014602Y+022811               S0      
317NNAME00191       VIA        MD0040PA06X+018160Y+019480               S0      
317NNAME00191       VIA        MD0040PA00X+018000Y+019850               S0      
317SMB_P_HUB_A1                 D0040PA01X+024660Y+019730               S0      
317SMB_P_HUB_A1                 D0040PA01X+024660Y+019320               S0      
327SMB_P_HUB_A1                 D0040PA01X+025994Y+019394               S0      
317SMB_P_HUB_A1     VIA        MD0040PA06X+024620Y+019360               S0      
317SMB_P_HUB_A1     VIA        MD0040PA00X+025010Y+019300               S0      
327NNAME00192                   D0040PA01X+010763Y+009887               S0      
317NNAME00192                   D0040PA01X+011667Y+010777               S0      
317NNAME00192       VIA        MD0040PA01X+011640Y+010380               S0      
327NNAME00193                   D0040PA01X+036364Y+002593               S0      
317NNAME00193                   D0040PA01X+037840Y+003010               S0      
317NNAME00193       VIA        MD0040PA01X+037480Y+002952               S0      
327NNAME00194                   D0040PA01X+036684Y+006293               S0      
317NNAME00194                   D0040PA01X+037560Y+007830               S0      
317NNAME00194       VIA        MD0040PA01X+037550Y+007410               S0      
327NNAME00195                   D0040PA01X+036364Y+002849               S0      
317NNAME00195                   D0040PA01X+037840Y+003420               S0      
317NNAME00195       VIA        MD0040PA01X+037035Y+003132               S0      
317NNAME00196                   D0040PA01X+037150Y+007830               S0      
327NNAME00196                   D0040PA01X+036684Y+006549               S0      
317NNAME00196       VIA        MD0040PA01X+037080Y+007280               S0      
327SMCLK_BMC_R                  D0040PA01X+007132Y+019584               S0      
317SMCLK_BMC_R                  D0040PA01X+006740Y+020700               S0      
317SMCLK_BMC_R      VIA        MD0040PA01X+006820Y+020320               S0      
327SMDAT_BMC_R                  D0040PA01X+006876Y+019584               S0      
317SMDAT_BMC_R                  D0040PA01X+006340Y+020700               S0      
317SMDAT_BMC_R      VIA        MD0040PA01X+006330Y+020300               S0      
317SMB_P_HUB_A2                 D0040PA01X+024660Y+018900               S0      
317SMB_P_HUB_A2                 D0040PA01X+024980Y+018490               S0      
327SMB_P_HUB_A2                 D0040PA01X+025994Y+019138               S0      
317SMB_P_HUB_A2     VIA        MD0040PA01X+025040Y+018910               S0      
317NNAME00197                   D0040PA01X+009590Y+020700               S0      
327NNAME00197                   D0040PA01X+008924Y+019584               S0      
317NNAME00197       VIA        MD0040PA01X+009490Y+019860               S0      
317NNAME00198                   D0040PA00X+012240Y+014811               S0      
317NNAME00198                   D0040PA01X+009570Y+017640               S0      
317NNAME00198       VIA        MD0040PA06X+009580Y+017570               S0      
317NNAME00198       VIA        MD0040PA00X+010000Y+017570               S0      
317NNAME00199                   D0040PA01X+010618Y+022322               S0      
317NNAME00199                   D0040PA00X+012240Y+022811               S0      
327NNAME00200                   D0040PA01X+011078Y+009572               S0      
317NNAME00200                   D0040PA01X+012100Y+010777               S0      
317NNAME00200       VIA        MD0040PA06X+010820Y+010030               S0      
317NNAME00200       VIA        MD0040PA00X+011175Y+009845               S0      
327NNAME00201                   D0040PA01X+011078Y+008981               S0      
317NNAME00201                   D0040PA01X+011177Y+010533               S0      
317NNAME00201                   D0040PA01X+010921Y+010978               S0      
317NNAME00201       VIA        MD0040PA06X+011360Y+009010               S0      
317NNAME00201       VIA        MD0040PA00X+010550Y+010950               S0      
317NNAME00201       VIA        MD0040PA00X+011078Y+008720               S0      
317NNAME00202                   D0040PA01X+028340Y+016840               S0      
327NNAME00202                   D0040PA01X+028214Y+017346               S0      
317NNAME00202       VIA        MD0040PA06X+027448Y+016790               S0      
317NNAME00202       VIA        MD0040PA00X+027440Y+016170               S0      
317PERST_SLOT_N                 D0040PA01X+012460Y+005190               S0      
327PERST_SLOT_N                 D0040PA01X+012034Y+005925               S0      
317PERST_SLOT_N                 D0040PA01X+012460Y+004350               S0      
317PERST_SLOT_N                 D0040PA01X+012460Y+004770               S0      
317PERST_SLOT_N     VIA        MD0040PA01X+012000Y+004850               S0      
317NNAME00203                   D0040PA01X+012800Y+005190               S0      
317NNAME00203                   D0040PA00X+016177Y+014811               S0      
317NNAME00203       VIA        MD0040PA06X+016140Y+006250               S0      
317NNAME00203       VIA        MD0040PA00X+016140Y+005870               S0      
317NNAME00204                   D0040PA00X+016177Y+022811               S0      
317NNAME00204                   D0040PA01X+012800Y+004770               S0      
317NNAME00204       VIA        MD0040PA06X+015430Y+006020               S0      
317NNAME00204       VIA        MD0040PA00X+015430Y+005640               S0      
317RESET_O_1                    D0040PA01X+014240Y+005870               S0      
317RESET_O_1                    D0040PA01X+009870Y+005730               S0      
317RESET_O_1                    D0040PA01X+012520Y+007460               S0      
317RESET_O_1                    D0040PA01X+013700Y+005290               S0      
317RESET_O_1        VIA        MD0040PA06X+012020Y+007890               S0      
317RESET_O_1        VIA        MD0040PA00X+010450Y+005620               S0      
317RESET_O_1        VIA        MD0040PA00X+012410Y+007890               S0      
317RESET_O_1        VIA        MD0040PA00X+013790Y+004940               S0      
327PERST_O_1_R                  D0040PA01X+010804Y+005945               S0      
317PERST_O_1_R                  D0040PA01X+009870Y+006070               S0      
317PERST_O_1_R      VIA        MD0040PA01X+010280Y+006170               S0      
317USB_RESET_N                  D0040PA01X+012800Y+004350               S0      
317USB_RESET_N                  D0040PA01X+044345Y+002961               S0      
317USB_RESET_N      VIA        MD0040PA01X+044340Y+002362               S0      
317USB_RESET_N      VIA        MD0040PA00X+015290Y+004650               S0      
317USB_RESET_N      VIA        MD0040PA00X+043890Y+001340               S0      
317PERST_N_1_R                  D0040PA01X+011580Y+007480               S0      
327PERST_N_1_R                  D0040PA01X+012290Y+006575               S0      
317PERST_N_1_R                  D0040PA01X+012180Y+007460               S0      
317PERST_N_1_R      VIA        MD0040PA01X+011750Y+007915               S0      
327PERST_N_1                    D0040PA01X+011316Y+006595               S0      
317PERST_N_1                    D0040PA01X+011240Y+007480               S0      
317PERST_N_1        VIA        MD0040PA01X+010860Y+007300               S0      
327NNAME00205                   D0040PA01X+011078Y+009178               S0      
317NNAME00205                   D0040PA01X+011782Y+009356               S0      
317NNAME00205                   D0040PA01X+011780Y+008936               S0      
317NNAME00205       VIA        MD0040PA01X+011740Y+008505               S0      
317NNAME00206                   D0040PA01X+009767Y+014891               S0      
327NNAME00206                   D0040PA01X+008529Y+014324               S0      
317NNAME00206       VIA        MD0040PA01X+009370Y+014920               S0      
317NNAME00207                   D0040PA01X+009764Y+015324               S0      
327NNAME00207                   D0040PA01X+008213Y+014639               S0      
317NNAME00207       VIA        MD0040PA01X+008970Y+015230               S0      
317NNAME00208                   D0040PA01X+009468Y+013180               S0      
317NNAME00208                   D0040PA01X+009469Y+013591               S0      
327NNAME00208                   D0040PA01X+008529Y+013733               S0      
317NNAME00208       VIA        MD0040PA01X+009100Y+013423               S0      
317NNAME00209                   D0040PA01X+009596Y+014406               S0      
327NNAME00209                   D0040PA01X+008529Y+013930               S0      
317NNAME00209                   D0040PA01X+009469Y+014004               S0      
317NNAME00209       VIA        MD0040PA01X+009097Y+013903               S0      
317NNAME00210                   D0040PA01X+020710Y+019580               S0      
327NNAME00210                   D0040PA01X+020578Y+018859               S0      
317NNAME00210       VIA        MD0040PA01X+021189Y+018900               S0      
317NNAME00211                   D0040PA01X+042640Y+002650               S0      
327NNAME00211                   D0040PA01X+042819Y+004486               S0      
317NNAME00211                   D0040PA01X+042646Y+003064               S0      
327NNAME00211                   D0040PA01X+039977Y+001241               S0      
317NNAME00211                   D0040PA01X+041380Y+001520               S0      
317NNAME00211       VIA        MD0040PA01X+041945Y+001677               S0      
327NNAME00212                   D0040PA01X+042425Y+004486               S0      
317NNAME00212                   D0040PA01X+042220Y+003070               S0      
317NNAME00212                   D0040PA01X+041380Y+001930               S0      
317NNAME00212                   D0040PA01X+042210Y+002640               S0      
327NNAME00212                   D0040PA01X+039721Y+001241               S0      
317NNAME00212       VIA        MD0040PA01X+040955Y+001897               S0      
327CFG_SEL1                     D0040PA01X+043016Y+004486               S0      
317CFG_SEL1                     D0040PA01X+043529Y+003301               S0      
317CFG_SEL1                     D0040PA01X+043942Y+003304               S0      
317CFG_SEL1         VIA        MD0040PA01X+043453Y+003742               S0      
327TP_USB_DP3                   D0040PA01X+041835Y+006756               S0      
317TP_USB_DP3                   D0040PA01X+041428Y+008068               S0      
317TP_USB_DP3       VIA        MD0040PA01X+040970Y+007720               S0      
327RBIAS                        D0040PA01X+043742Y+006197               S0      
317RBIAS                        D0040PA01X+044826Y+006654               S0      
317RBIAS            VIA        MD0040PA01X+044826Y+007030               S0      
327USB_DN2                      D0040PA01X+042425Y+006726               S0      
317USB_DN2                      D0040PA01X+042670Y+008070               S0      
327TP_USB_DN3                   D0040PA01X+042031Y+006726               S0      
317TP_USB_DN3                   D0040PA01X+041844Y+008065               S0      
317TP_USB_DN3       VIA        MD0040PA01X+041650Y+007620               S0      
327USB_DP2                      D0040PA01X+042228Y+006726               S0      
317USB_DP2                      D0040PA01X+042264Y+008068               S0      
317NON_REM0                     D0040PA01X+045040Y+003710               S0      
327NON_REM0                     D0040PA01X+043772Y+004819               S0      
317NON_REM0                     D0040PA01X+045460Y+003710               S0      
317NON_REM0         VIA        MD0040PA01X+044470Y+004190               S0      
317NNAME00213                   D0040PA01X+045041Y+004847               S0      
327NNAME00213                   D0040PA01X+043742Y+005212               S0      
327NNAME00214                   D0040PA01X+043742Y+005409               S0      
317NNAME00214                   D0040PA01X+045039Y+005254               S0      
327USB_RESET_R_N                D0040PA01X+043213Y+004486               S0      
317USB_RESET_R_N                D0040PA01X+044345Y+003301               S0      
317USB_RESET_R_N    VIA        MD0040PA01X+043980Y+003710               S0      
317NNAME00215                   D0040PA01X+040020Y+000110               S0      
327NNAME00215                   D0040PA01X+039465Y+001241               S0      
317NNAME00215       VIA        MD0040PA01X+039600Y+000500               S0      
327NNAME00216                   D0040PA01X+043213Y+006726               S0      
317NNAME00216                   D0040PA00X+025232Y+015598               S0      
317NNAME00216       VIA        MD0040PA00X+045374Y+010515               S0      
327NNAME00217                   D0040PA01X+043409Y+006756               S0      
317NNAME00217                   D0040PA00X+025626Y+014811               S0      
317NNAME00217       VIA        MD0040PA00X+045725Y+010515               S0      
317NNAME00218                   D0040PA01X+044860Y+010940               S0      
317NNAME00218                   D0040PA00X+044917Y+013039               S0      
327NNAME00219                   D0040PA01X+042819Y+006726               S0      
317NNAME00219                   D0040PA00X+025232Y+023598               S0      
317NNAME00219       VIA        MD0040PA00X+045138Y+009172               S0      
327NNAME00220                   D0040PA01X+043016Y+006726               S0      
317NNAME00220                   D0040PA00X+025626Y+022811               S0      
317NNAME00220       VIA        MD0040PA00X+045138Y+008821               S0      
317NNAME00221                   D0040PA00X+044917Y+021039               S0      
317NNAME00221                   D0040PA01X+047150Y+020950               S0      
327TP_USB_OCS_N1                D0040PA01X+041502Y+005803               S0      
317TP_USB_OCS_N1                D0040PA01X+040402Y+006133               S0      
327TP_USB_OCS_N2                D0040PA01X+041502Y+005015               S0      
317TP_USB_OCS_N2                D0040PA01X+040736Y+004548               S0      
317TP_USB_OCS_N3                D0040PA01X+040645Y+004044               S0      
327TP_USB_OCS_N3                D0040PA01X+041835Y+004456               S0      
317TP_USB_OCS_N4                D0040PA01X+041097Y+003750               S0      
327TP_USB_OCS_N4                D0040PA01X+042228Y+004486               S0      
999
